G04 ================== begin FILE IDENTIFICATION RECORD ==================*
G04 Layout Name:  D:/<user>/Wistron_project/16318-2/gbr/16318-2.brd*
G04 Film Name:    L6*
G04 File Format:  Gerber RS274X*
G04 File Origin:  Cadence Allegro 16.5-S056*
G04 Origin Date:  Mon Aug 07 11:09:47 2017*
G04 *
G04 Layer:  VIA CLASS/L6*
G04 Layer:  PIN/L6*
G04 Layer:  ETCH/L6*
G04 Layer:  DRAWING FORMAT/LAYER_PCB_STORY*
G04 Layer:  DRAWING FORMAT/LAYER_L6*
G04 *
G04 Offset:    (0.00 0.00)*
G04 Mirror:    No*
G04 Mode:      Positive*
G04 Rotation:  0*
G04 FullContactRelief:  No*
G04 UndefLineWidth:     6.00*
G04 ================== end FILE IDENTIFICATION RECORD ====================*
%FSLAX35Y35*MOIN*%
%IR0*IPPOS*OFA0.00000B0.00000*MIA0B0*SFA1.00000B1.00000*%
%ADD11C,.02*%
%ADD14C,.03*%
%ADD16C,.022*%
%ADD13C,.042*%
%ADD12C,.018*%
%ADD10C,.028*%
%ADD15C,.029*%
%ADD17C,.01*%
%ADD18C,.004*%
%ADD19C,.005*%
%ADD20C,.006*%
%ADD21C,.0035*%
%ADD22C,.0055*%
%ADD23C,.03004*%
%ADD24C,.05204*%
%ADD25C,.04404*%
G75*
%LPD*%
G75*
G36*
G01X6002Y722992D02*
X23394Y757778D01*
X40764D01*
G02X40940Y757019I0J-400D01*
G03X35305Y752780I8273J-16862D01*
G01X26483D01*
X11125Y722062D01*
X10896D01*
X10750Y721916D01*
Y721708D01*
X10896Y721562D01*
X11000D01*
Y11000D01*
X109197D01*
Y40396D01*
X109343Y40437D01*
G03Y48147I-1075J3855D01*
G01X109197Y48188D01*
Y429331D01*
G02X109850Y433698I14937J-1D01*
G01X114587D01*
G02X114956Y433145I0J-400D01*
G03X114196Y429331I9179J-3812D01*
G01Y6002D01*
X6002D01*
Y722992D01*
G37*
G36*
G01X63121Y752780D02*
G03X57486Y757019I-13908J-12623D01*
G02X57662Y757778I176J359D01*
G01X355907D01*
G02X356080Y757018I0J-400D01*
G03X350373Y752780I8094J-16861D01*
G01X63121D01*
G37*
G36*
G01X199650Y582350D02*
X198350Y583650D01*
Y585753D01*
G03X198469Y585933I-1107J861D01*
G02X199168I350J-195D01*
G03X201618Y585932I1225J681D01*
G02X202317I349J-194D01*
G03X204767Y585933I1225J682D01*
G02X205467I350J-194D01*
G03X206010Y585389I1226J680D01*
G02Y584690I-194J-350D01*
G03X205405Y582909I682J-1225D01*
G02X205038Y582350I-367J-159D01*
G01X199650D01*
G37*
G36*
G01X204767Y587295D02*
G03X202317Y587296I-1225J-681D01*
G02X201618I-350J194D01*
G03X199168I-1225J-682D01*
G02X198469I-350J195D01*
G03X198350Y587477I-1227J-677D01*
G01Y588904D01*
G03X198632Y589574I-1107J860D01*
G01X198641Y589641D01*
X200515Y591515D01*
X200581Y591524D01*
G03X201618Y592231I-188J1389D01*
G02X202317I349J-194D01*
G03X203798Y594291I1225J682D01*
G02Y594685I37J197D01*
G03X203849Y594695I-244J1380D01*
G01X203871Y594700D01*
X206363D01*
X206385Y594695D01*
G03X206999I307J1368D01*
G01X207021Y594700D01*
X208150D01*
X208700Y594150D01*
Y593730D01*
X208667Y593680D01*
G03X208700Y592098I1174J-767D01*
G01Y590659D01*
G03X208585Y590488I1144J-893D01*
G02X207895Y590483I-346J200D01*
G03X206010Y588538I-1203J-720D01*
G02Y587839I-194J-350D01*
G03X205467Y587295I683J-1224D01*
G02X204767I-350J194D01*
G37*
G36*
G01X293522Y6002D02*
Y34521D01*
X298520D01*
Y11000D01*
X314847D01*
X314849Y10998D01*
X316418D01*
Y6002D01*
X293522D01*
G37*
G36*
G01X397143Y722062D02*
X381785Y752780D01*
X377973D01*
X377914Y752844D01*
G03X372266Y757018I-13742J-12686D01*
G02X372439Y757778I173J360D01*
G01X384874D01*
X402266Y722992D01*
Y722062D01*
X397143D01*
G37*
G36*
G01X574112Y722993D02*
X591504Y757778D01*
X603939D01*
G02X604112Y757018I0J-400D01*
G03X598464Y752844I8094J-16860D01*
G01X598405Y752780D01*
X594593D01*
X579110Y721812D01*
Y384295D01*
X574112D01*
Y722993D01*
G37*
G36*
G01X626005Y752780D02*
G03X620298Y757018I-13801J-12623D01*
G02X620471Y757778I173J360D01*
G01X867718D01*
G02X867891Y757018I0J-400D01*
G03X862184Y752780I8094J-16861D01*
G01X626005D01*
G37*
G36*
G01X914197Y721812D02*
X898714Y752780D01*
X889784D01*
G03X884077Y757018I-13801J-12623D01*
G02X884250Y757778I173J360D01*
G01X901803D01*
X919196Y722993D01*
Y6002D01*
X741903D01*
Y11000D01*
X914197D01*
Y721812D01*
G37*
G36*
G01X798400Y247400D02*
X797942Y247858D01*
X797938Y247862D01*
G03X797883Y247921I-1125J-994D01*
G01X797293Y248510D01*
X797290D01*
X794320Y251480D01*
X792810D01*
X792090Y250760D01*
X789253D01*
X789249Y250764D01*
X782660D01*
X782656Y250760D01*
X780770D01*
X779460Y252070D01*
Y259229D01*
X779462Y259243D01*
G03Y259679I-1486J218D01*
G01X779460Y259693D01*
Y262411D01*
X779461Y262422D01*
G03Y262730I-1494J154D01*
G01X779460Y262741D01*
Y265529D01*
X779462Y265543D01*
G03Y265979I-1486J218D01*
G01X779460Y265993D01*
Y266620D01*
X778510Y267570D01*
X776479D01*
G02X776132Y268168I0J400D01*
G03X773520I-1306J742D01*
G02X773173Y267570I-347J-198D01*
G01X771240D01*
X770800Y268010D01*
Y279400D01*
X771394Y279994D01*
X771491Y279983D01*
G03X773160Y281652I178J1491D01*
G01X773149Y281749D01*
X775700Y284300D01*
X779100D01*
X780300Y283100D01*
X785500D01*
X786000Y282600D01*
Y280700D01*
X785100Y279800D01*
X784488D01*
X784473Y279802D01*
G03X784013I-230J-1484D01*
G01X783998Y279800D01*
X783300D01*
X782600Y279100D01*
Y277500D01*
X783500Y276600D01*
X789100D01*
X789600Y276100D01*
Y274400D01*
X788900Y273700D01*
X780500D01*
X779600Y272800D01*
Y272383D01*
X779596Y272363D01*
G03Y271731I1468J-316D01*
G01X779600Y271711D01*
Y271300D01*
X780600Y270300D01*
X788100D01*
X788800Y269600D01*
Y265200D01*
X792900Y261100D01*
X796617D01*
X796630Y261098D01*
G03X797014I192J1490D01*
G01X797027Y261100D01*
X799767D01*
X799780Y261098D01*
G03X800164I192J1490D01*
G01X800177Y261100D01*
X800900D01*
X801500Y261700D01*
Y267300D01*
X798000Y270800D01*
X796400D01*
X795900Y271300D01*
Y272700D01*
X795950Y272750D01*
Y274750D01*
X797100Y275900D01*
X800700D01*
X801600Y276800D01*
Y278800D01*
X801294Y279106D01*
G03X800760Y279640I-1295J-761D01*
G01X800200Y280200D01*
X796600D01*
X795700Y281100D01*
Y284500D01*
X798400Y287200D01*
Y288700D01*
X797600Y289500D01*
X796100D01*
X795800Y289800D01*
Y293900D01*
X797400Y295500D01*
X797600D01*
X798200Y296100D01*
Y296564D01*
X798219Y296604D01*
G03X798351Y297074I-1370J638D01*
G01X798360Y297158D01*
Y297253D01*
G03X798219Y297882I-1511J-8D01*
G01X798200Y297922D01*
Y298400D01*
X795000Y301600D01*
Y305100D01*
X795176Y305276D01*
Y313164D01*
X804401Y322389D01*
X821960D01*
X825562Y325991D01*
X825646D01*
G03X827848Y328194I0J2202D01*
G01Y328277D01*
X829626Y330055D01*
Y350693D01*
X830585Y351652D01*
Y352128D01*
X830593Y352156D01*
G03Y353644I-2493J744D01*
G01X830585Y353672D01*
Y354466D01*
X829650Y355401D01*
X828818D01*
X828792Y355408D01*
G03X827408I-692J-2508D01*
G01X827382Y355401D01*
X821050D01*
X819783Y356668D01*
Y365659D01*
X820960Y366836D01*
X838972D01*
X848300Y357508D01*
Y326058D01*
X816849Y294607D01*
Y258349D01*
X813125Y254625D01*
Y251825D01*
X808775Y247475D01*
X808709Y247466D01*
G03X808465Y247410I213J-1487D01*
G01X808435Y247400D01*
X798400D01*
G37*
%LPC*%
G75*
G36*
G01X776045Y274350D02*
G02X776032Y276017I-1256J824D01*
G03X776697Y276022I331J225D01*
G02X777110Y276441I1256J-824D01*
G03Y277104I-224J332D01*
G02X777096Y279580I843J1243D01*
G03X777088Y280242I-229J328D01*
G02X778772Y280263I826J1254D01*
G03X778780Y279601I229J-328D01*
G02X778796Y277104I-827J-1254D01*
G03Y276441I224J-332D01*
G02X776710Y274355I-843J-1243D01*
G03X776045Y274350I-331J-225D01*
G37*
G36*
G01X785136Y254394D02*
G02X783410Y254389I-859J-1232D01*
G03X783408Y255044I-230J327D01*
G02X783425Y257520I859J1232D01*
G03Y258182I-224J331D01*
G02X785109I842J1244D01*
G03Y257520I224J-331D01*
G02X785134Y255049I-842J-1244D01*
G03X785136Y254394I230J-327D01*
G37*
G36*
G01X791388Y254397D02*
G02X789691Y254382I-838J-1247D01*
G03X789685Y255042I-229J328D01*
G02X789720Y257558I838J1247D01*
G03X789726Y258231I-213J338D01*
G02X791354Y258217I825J1255D01*
G03X791348Y257544I213J-338D01*
G02X791784Y257104I-826J-1254D01*
G03X792453Y257099I336J217D01*
G02X794925Y257131I1247J-837D01*
G03X795582Y257136I327J231D01*
G02X798060Y257139I1240J-847D01*
G03X798723Y257143I330J226D01*
G02X801220Y257145I1249J-834D01*
G03X801888Y257151I332J223D01*
G02X802294Y257570I1261J-816D01*
G03X802296Y258226I-228J329D01*
G02X804016Y258220I864J1228D01*
G03X804014Y257564I228J-329D01*
G02X801902Y255500I-864J-1228D01*
G03X801234Y255494I-332J-223D01*
G02X798734Y255459I-1262J815D01*
G03X798071Y255455I-330J-226D01*
G02X795597Y255420I-1249J834D01*
G03X794940Y255415I-327J-231D01*
G02X792439Y255447I-1240J847D01*
G03X791770Y255452I-336J-217D01*
G02X791382Y255057I-1247J837D01*
G03X791388Y254397I229J-328D01*
G37*
G54D23*
X799991Y249972D03*
X799999Y290944D03*
Y284645D03*
X799974Y272058D03*
X806968Y253464D03*
X807177Y261023D03*
X803300Y303700D03*
X814450Y306950D03*
X810079Y271264D03*
X809968Y290464D03*
X808400Y300900D03*
X812164Y279674D03*
G54D24*
X841100Y332300D03*
X842600Y339400D03*
X842900Y347200D03*
X840800Y352800D03*
G54D25*
X823250Y319350D03*
X811600Y317300D03*
%LPD*%
G75*
G54D10*
X8500Y18279D03*
Y28279D03*
Y38279D03*
Y48279D03*
Y58279D03*
Y68279D03*
X13721Y8500D03*
X8500Y13279D03*
Y23279D03*
Y33279D03*
Y43279D03*
Y53279D03*
Y63279D03*
Y78279D03*
Y88279D03*
Y98279D03*
Y108279D03*
Y118279D03*
Y128279D03*
Y73279D03*
Y83279D03*
Y93279D03*
Y103279D03*
Y113279D03*
Y123279D03*
Y133279D03*
Y138279D03*
Y148279D03*
Y158279D03*
Y168279D03*
Y178279D03*
Y188279D03*
Y198279D03*
Y143279D03*
Y153279D03*
Y163279D03*
Y173279D03*
Y183279D03*
Y193279D03*
Y208279D03*
Y218279D03*
Y228279D03*
Y238279D03*
Y248279D03*
Y258279D03*
Y203279D03*
Y213279D03*
Y223279D03*
Y233279D03*
Y243279D03*
Y253279D03*
Y263279D03*
Y268279D03*
Y278279D03*
Y288279D03*
Y298279D03*
Y308279D03*
Y318279D03*
Y328279D03*
Y273279D03*
Y283279D03*
Y293279D03*
Y303279D03*
Y313279D03*
Y323279D03*
Y338279D03*
Y348279D03*
Y358279D03*
Y368279D03*
Y378279D03*
Y388279D03*
Y333279D03*
Y343279D03*
Y353279D03*
Y363279D03*
Y373279D03*
Y383279D03*
Y393279D03*
Y398279D03*
Y408279D03*
Y418279D03*
Y428279D03*
Y438279D03*
Y448279D03*
Y458279D03*
Y403279D03*
Y413279D03*
Y423279D03*
Y433279D03*
Y443279D03*
Y453279D03*
Y468279D03*
Y478279D03*
Y488279D03*
Y498279D03*
Y508279D03*
Y518279D03*
Y528279D03*
Y463279D03*
Y473279D03*
Y483279D03*
Y493279D03*
Y503279D03*
Y513279D03*
Y523279D03*
Y538279D03*
Y548279D03*
Y558279D03*
Y568279D03*
Y578279D03*
Y588279D03*
Y533279D03*
Y543279D03*
Y553279D03*
Y563279D03*
Y573279D03*
Y583279D03*
Y593279D03*
Y598279D03*
Y608279D03*
Y618279D03*
Y628279D03*
Y638279D03*
Y648279D03*
Y658279D03*
Y603279D03*
Y613279D03*
Y623279D03*
Y633279D03*
Y643279D03*
Y653279D03*
Y668279D03*
Y678279D03*
Y688279D03*
Y698279D03*
Y708279D03*
Y718279D03*
Y663279D03*
Y673279D03*
Y683279D03*
Y693279D03*
Y703279D03*
Y713279D03*
X8892Y723187D03*
X11090Y727806D03*
X13500Y732400D03*
X78721Y8500D03*
X68721D03*
X58721D03*
X48721D03*
X38721D03*
X28721D03*
X18721D03*
X73721D03*
X53721D03*
X43721D03*
X33721D03*
X23721D03*
X63721D03*
X28100Y755600D03*
X33100D03*
X69057Y755280D03*
X74057D03*
X20300Y746200D03*
X15800Y736900D03*
X18100Y741500D03*
X22600Y750800D03*
X79057Y755280D03*
X108721Y8500D03*
X98721D03*
X88721D03*
X112197Y65406D03*
Y60406D03*
Y55406D03*
X103721Y8500D03*
X93721D03*
X83721D03*
X112197Y75406D03*
Y85406D03*
Y95406D03*
Y105406D03*
Y115406D03*
Y120406D03*
Y110406D03*
Y100406D03*
Y90406D03*
Y80406D03*
Y70406D03*
Y145406D03*
Y195406D03*
Y185406D03*
Y175406D03*
Y165406D03*
Y155406D03*
Y200406D03*
Y190406D03*
Y180406D03*
Y170406D03*
Y160406D03*
Y150406D03*
Y265406D03*
Y255406D03*
Y245406D03*
Y235406D03*
Y225406D03*
Y215406D03*
Y205406D03*
Y260406D03*
Y250406D03*
Y240406D03*
Y230406D03*
Y220406D03*
Y210406D03*
Y325406D03*
Y315406D03*
Y305406D03*
Y295406D03*
Y285406D03*
Y275406D03*
Y330406D03*
Y320406D03*
Y310406D03*
Y300406D03*
Y290406D03*
Y280406D03*
Y270406D03*
Y390406D03*
Y380406D03*
Y370406D03*
Y360406D03*
Y350406D03*
Y395406D03*
Y385406D03*
Y375406D03*
Y365406D03*
Y355406D03*
Y345406D03*
Y335406D03*
Y340406D03*
Y420406D03*
Y410406D03*
Y400406D03*
Y425406D03*
Y415406D03*
Y405406D03*
X80334Y625175D03*
X144057Y755280D03*
X134057D03*
X124057D03*
X114057D03*
X104057D03*
X94057D03*
X84057D03*
X89057D03*
X99057D03*
X109057D03*
X119057D03*
X129057D03*
X139057D03*
X204057D03*
X194057D03*
X184057D03*
X174057D03*
X164057D03*
X154057D03*
X149057D03*
X159057D03*
X169057D03*
X179057D03*
X189057D03*
X199057D03*
X209057D03*
X274057D03*
X264057D03*
X254057D03*
X244057D03*
X234057D03*
X224057D03*
X214057D03*
X219057D03*
X229057D03*
X239057D03*
X249057D03*
X259057D03*
X269057D03*
X315120Y8500D03*
X310120D03*
X305120D03*
X300120D03*
X296020Y9420D03*
Y14420D03*
Y19420D03*
Y24420D03*
Y29420D03*
X335132Y195874D03*
X334057Y755280D03*
X324057D03*
X314057D03*
X304057D03*
X294057D03*
X284057D03*
X279057D03*
X289057D03*
X299057D03*
X309057D03*
X319057D03*
X329057D03*
X339057D03*
X381638D03*
X384809Y752321D03*
X387045Y747849D03*
X389281Y743376D03*
X391517Y738904D03*
X393753Y734432D03*
X395989Y729960D03*
X398225Y725488D03*
X344057Y755280D03*
X576610Y388416D03*
Y393416D03*
Y398416D03*
Y403416D03*
Y408416D03*
Y413416D03*
Y418416D03*
Y423416D03*
Y428416D03*
Y433416D03*
Y438416D03*
Y443416D03*
Y448416D03*
Y453416D03*
Y458416D03*
Y463416D03*
Y468416D03*
Y473416D03*
Y478416D03*
Y483416D03*
Y488416D03*
Y493416D03*
Y498416D03*
Y503416D03*
Y508416D03*
Y513416D03*
Y518416D03*
Y523416D03*
Y528416D03*
Y533416D03*
Y538416D03*
Y543416D03*
Y548416D03*
Y553416D03*
Y558416D03*
Y563416D03*
Y568416D03*
Y573416D03*
Y578416D03*
Y583416D03*
Y588416D03*
Y593416D03*
Y598416D03*
Y603416D03*
Y608416D03*
Y613416D03*
Y618416D03*
Y623416D03*
Y628416D03*
Y633416D03*
Y638416D03*
Y643416D03*
Y648416D03*
Y653416D03*
Y658416D03*
Y663416D03*
Y668416D03*
Y673416D03*
Y678416D03*
Y683416D03*
Y688416D03*
Y693416D03*
Y698416D03*
Y703416D03*
Y708416D03*
Y713416D03*
Y718416D03*
X577063Y723309D03*
X579299Y727781D03*
X581535Y732253D03*
X583771Y736725D03*
X586007Y741198D03*
X588243Y745670D03*
X590479Y750142D03*
X592715Y754614D03*
X659722Y755280D03*
X649722D03*
X639722D03*
X634722D03*
X644722D03*
X654722D03*
X664722D03*
X729722D03*
X719722D03*
X709722D03*
X699722D03*
X689722D03*
X679722D03*
X669722D03*
X674722D03*
X684722D03*
X694722D03*
X704722D03*
X714722D03*
X724722D03*
X734722D03*
X780100Y8500D03*
X775100D03*
X770100D03*
X765100D03*
X760100D03*
X755100D03*
X750100D03*
X745100D03*
X787895D03*
X797895D03*
X792895D03*
X799722Y755280D03*
X789722D03*
X779722D03*
X769722D03*
X759722D03*
X749722D03*
X739722D03*
X744722D03*
X754722D03*
X764722D03*
X774722D03*
X784722D03*
X794722D03*
X807895Y8500D03*
X817895D03*
X827895D03*
X837895D03*
X847895D03*
X857895D03*
X862895D03*
X852895D03*
X842895D03*
X832895D03*
X822895D03*
X812895D03*
X802895D03*
X826993Y358840D03*
X821502Y358356D03*
X827145Y363638D03*
X821653Y363488D03*
X849722Y755280D03*
X839722D03*
X829722D03*
X819722D03*
X809722D03*
X804722D03*
X814722D03*
X824722D03*
X834722D03*
X844722D03*
X854722D03*
X867895Y8500D03*
X877895D03*
X887895D03*
X897895D03*
X907895D03*
X916697Y19698D03*
Y29698D03*
Y39698D03*
Y49698D03*
Y59698D03*
Y69698D03*
Y64698D03*
Y54698D03*
Y44698D03*
Y34698D03*
Y24698D03*
Y14698D03*
X912895Y8500D03*
X902895D03*
X892895D03*
X882895D03*
X872895D03*
X916697Y79698D03*
Y89698D03*
Y99698D03*
Y109698D03*
Y119698D03*
Y129698D03*
Y134698D03*
Y124698D03*
Y114698D03*
Y104698D03*
Y94698D03*
Y84698D03*
Y74698D03*
Y139698D03*
Y149698D03*
Y159698D03*
Y169698D03*
Y179698D03*
Y189698D03*
Y199698D03*
Y194698D03*
Y184698D03*
Y174698D03*
Y164698D03*
Y154698D03*
Y144698D03*
Y209698D03*
Y219698D03*
Y229698D03*
Y239698D03*
Y249698D03*
Y259698D03*
Y264698D03*
Y254698D03*
Y244698D03*
Y234698D03*
Y224698D03*
Y214698D03*
Y204698D03*
Y269698D03*
Y279698D03*
Y289698D03*
Y299698D03*
Y309698D03*
Y319698D03*
Y329698D03*
Y324698D03*
Y314698D03*
Y304698D03*
Y294698D03*
Y284698D03*
Y274698D03*
Y339698D03*
Y349698D03*
Y359698D03*
Y369698D03*
Y379698D03*
Y389698D03*
Y394698D03*
Y384698D03*
Y374698D03*
Y364698D03*
Y354698D03*
Y344698D03*
Y334698D03*
Y399698D03*
Y409698D03*
Y419698D03*
Y429698D03*
Y439698D03*
Y449698D03*
Y459698D03*
Y454698D03*
Y444698D03*
Y434698D03*
Y424698D03*
Y414698D03*
Y404698D03*
Y469698D03*
Y479698D03*
Y489698D03*
Y499698D03*
Y509698D03*
Y519698D03*
Y524698D03*
Y514698D03*
Y504698D03*
Y494698D03*
Y484698D03*
Y474698D03*
Y464698D03*
Y529698D03*
Y539698D03*
Y549698D03*
Y559698D03*
Y569698D03*
Y579698D03*
Y589698D03*
Y584698D03*
Y574698D03*
Y564698D03*
Y554698D03*
Y544698D03*
Y534698D03*
Y599698D03*
Y609698D03*
Y619698D03*
Y629698D03*
Y639698D03*
Y649698D03*
Y659698D03*
Y654698D03*
Y644698D03*
Y634698D03*
Y624698D03*
Y614698D03*
Y604698D03*
Y594698D03*
Y669698D03*
Y679698D03*
Y689698D03*
Y699698D03*
Y709698D03*
Y719698D03*
Y714698D03*
Y704698D03*
Y694698D03*
Y684698D03*
Y674698D03*
Y664698D03*
X914700Y726100D03*
X912436Y730603D03*
X910200Y735300D03*
X907564Y739747D03*
X905500Y744400D03*
X903192Y748791D03*
X900800Y753700D03*
X894722Y755280D03*
G54D20*
G01X13215Y-125739D02*
X14089Y-124864D01*
X14744Y-123406D01*
X15181Y-121363D01*
X14744Y-119614D01*
X13871Y-118447D01*
X12342Y-117572D01*
X6447D01*
Y-135072D01*
X13652D01*
X15181Y-133906D01*
X16054Y-132155D01*
X16491Y-130114D01*
X16054Y-128072D01*
X14744Y-126322D01*
X13215Y-125739D01*
X6447D01*
G01X25912Y-135072D02*
Y-123406D01*
G01Y-125739D02*
X27004Y-124572D01*
X28096Y-123697D01*
X29624Y-123406D01*
X30715Y-123697D01*
X32026Y-124572D01*
G01X41884Y-140322D02*
X43194Y-140905D01*
X44941Y-140322D01*
X46032Y-139156D01*
X46906Y-137697D01*
X48215Y-133031D01*
X51054Y-123406D01*
G01X44067D02*
X48215Y-133031D01*
G01X67462Y-124864D02*
X65934Y-123697D01*
X64624Y-123406D01*
X62877Y-123989D01*
X61567Y-125155D01*
X60694Y-127197D01*
X60475Y-129239D01*
X60694Y-131281D01*
X61567Y-133031D01*
X62877Y-134489D01*
X64624Y-135072D01*
X66152Y-134489D01*
X67462Y-133322D01*
G01X78194Y-127197D02*
X85181D01*
X84526Y-125155D01*
X83434Y-123989D01*
X81906Y-123406D01*
X80377Y-123697D01*
X79067Y-124572D01*
X78194Y-126614D01*
X77757Y-128364D01*
Y-130114D01*
X78194Y-131864D01*
X79286Y-133614D01*
X80596Y-134780D01*
X82124Y-135072D01*
X83652Y-134489D01*
X85181Y-132739D01*
G01X121272Y-119031D02*
X119962Y-118155D01*
X118434Y-117572D01*
X116687D01*
X114722Y-118447D01*
X113194Y-119905D01*
X112102Y-121656D01*
X111229Y-124572D01*
X111010Y-127197D01*
X111447Y-129822D01*
X112102Y-131572D01*
X113412Y-133322D01*
X114941Y-134489D01*
X116469Y-135072D01*
X117997D01*
X119526Y-134489D01*
X120836Y-133614D01*
X121928Y-132448D01*
G01X137899Y-135072D02*
Y-123406D01*
G01Y-125447D02*
X137026Y-124281D01*
X135715Y-123697D01*
X134187Y-123406D01*
X132659Y-123989D01*
X131349Y-125155D01*
X130475Y-126905D01*
X130039Y-129239D01*
X130475Y-131572D01*
X131349Y-133322D01*
X132659Y-134489D01*
X134187Y-135072D01*
X135715Y-134780D01*
X137026Y-133906D01*
X137899Y-132739D01*
G01X147757Y-135072D02*
Y-123406D01*
G01Y-126322D02*
X148631Y-124864D01*
X149941Y-123697D01*
X151687Y-123406D01*
X153215Y-123697D01*
X154526Y-124864D01*
X155181Y-126905D01*
Y-135072D01*
G01X164384Y-140322D02*
X165694Y-140905D01*
X167441Y-140322D01*
X168532Y-139156D01*
X169406Y-137697D01*
X170715Y-133031D01*
X173554Y-123406D01*
G01X166567D02*
X170715Y-133031D01*
G01X186469Y-135072D02*
X185159Y-134780D01*
X183849Y-133614D01*
X182975Y-131572D01*
X182539Y-129239D01*
X182975Y-126905D01*
X183849Y-124864D01*
X185159Y-123697D01*
X186469Y-123406D01*
X187779Y-123697D01*
X189089Y-124864D01*
X189962Y-126905D01*
X190181Y-129239D01*
X189962Y-131572D01*
X189089Y-133614D01*
X187779Y-134780D01*
X186469Y-135072D01*
G01X200257D02*
Y-123406D01*
G01Y-126322D02*
X201131Y-124864D01*
X202441Y-123697D01*
X204187Y-123406D01*
X205715Y-123697D01*
X207026Y-124864D01*
X207681Y-126905D01*
Y-135072D01*
G01X236349Y-117572D02*
X241589D01*
G01X238969D02*
Y-135072D01*
G01X236349D02*
X241589D01*
G01X256469D02*
X254722Y-134780D01*
X253194Y-133614D01*
X251884Y-131864D01*
X251010Y-129822D01*
X250574Y-127489D01*
Y-125155D01*
X251010Y-122822D01*
X251884Y-120780D01*
X253194Y-119031D01*
X254722Y-117864D01*
X256469Y-117572D01*
X258215Y-117864D01*
X259744Y-119031D01*
X261054Y-120780D01*
X261928Y-122822D01*
X262364Y-125155D01*
Y-127489D01*
X261928Y-129822D01*
X261054Y-131864D01*
X259744Y-133614D01*
X258215Y-134780D01*
X256469Y-135072D01*
G01X268292D02*
Y-117572D01*
X273969Y-132155D01*
X279646Y-117572D01*
Y-135072D01*
G01X307877Y-140905D02*
X305694Y-137989D01*
X304602Y-135072D01*
Y-123406D01*
X305694Y-120489D01*
X307877Y-117572D01*
G01X321010Y-123406D02*
X323631Y-135072D01*
X326469Y-123406D01*
X329307Y-135072D01*
X331928Y-123406D01*
G01X340039Y-135655D02*
X347899Y-117572D01*
G01X376349D02*
X381589D01*
G01X378969D02*
Y-135072D01*
G01X376349D02*
X381589D01*
G01X396469D02*
X394722Y-134780D01*
X393194Y-133614D01*
X391884Y-131864D01*
X391010Y-129822D01*
X390574Y-127489D01*
Y-125155D01*
X391010Y-122822D01*
X391884Y-120780D01*
X393194Y-119031D01*
X394722Y-117864D01*
X396469Y-117572D01*
X398215Y-117864D01*
X399744Y-119031D01*
X401054Y-120780D01*
X401928Y-122822D01*
X402364Y-125155D01*
Y-127489D01*
X401928Y-129822D01*
X401054Y-131864D01*
X399744Y-133614D01*
X398215Y-134780D01*
X396469Y-135072D01*
G01X418772Y-119031D02*
X417462Y-118155D01*
X415934Y-117572D01*
X414187D01*
X412222Y-118447D01*
X410694Y-119905D01*
X409602Y-121656D01*
X408729Y-124572D01*
X408510Y-127197D01*
X408947Y-129822D01*
X409602Y-131572D01*
X410912Y-133322D01*
X412441Y-134489D01*
X413969Y-135072D01*
X415497D01*
X417026Y-134489D01*
X418336Y-133614D01*
X419428Y-132448D01*
G01X432561Y-140905D02*
X434744Y-137989D01*
X435836Y-135072D01*
Y-123406D01*
X434744Y-120489D01*
X432561Y-117572D01*
G01X180792Y-90072D02*
Y-72572D01*
X186469Y-87155D01*
X192146Y-72572D01*
Y-90072D01*
G01X203969D02*
X202659Y-89780D01*
X201349Y-88614D01*
X200475Y-86572D01*
X200039Y-84239D01*
X200475Y-81905D01*
X201349Y-79864D01*
X202659Y-78697D01*
X203969Y-78406D01*
X205279Y-78697D01*
X206589Y-79864D01*
X207462Y-81905D01*
X207681Y-84239D01*
X207462Y-86572D01*
X206589Y-88614D01*
X205279Y-89780D01*
X203969Y-90072D01*
G01X225399Y-72572D02*
Y-90072D01*
G01Y-87448D02*
X224526Y-88906D01*
X223215Y-89780D01*
X221687Y-90072D01*
X219941Y-89489D01*
X218631Y-88031D01*
X217757Y-86281D01*
X217539Y-84239D01*
X217757Y-82197D01*
X218631Y-80447D01*
X219941Y-78989D01*
X221687Y-78406D01*
X223215Y-78697D01*
X224307Y-79281D01*
X225399Y-80447D01*
G01X235694Y-82197D02*
X242681D01*
X242026Y-80155D01*
X240934Y-78989D01*
X239406Y-78406D01*
X237877Y-78697D01*
X236567Y-79572D01*
X235694Y-81614D01*
X235257Y-83364D01*
Y-85114D01*
X235694Y-86864D01*
X236786Y-88614D01*
X238096Y-89780D01*
X239624Y-90072D01*
X241152Y-89489D01*
X242681Y-87739D01*
G01X256469Y-90072D02*
Y-72572D01*
G01X490269Y-135072D02*
Y-117572D01*
X487649Y-121072D01*
G01Y-135072D02*
X492889D01*
G01X503621Y-127781D02*
X505149Y-125739D01*
X506459Y-124572D01*
X508206Y-123989D01*
X509734Y-124572D01*
X510826Y-125739D01*
X511699Y-127489D01*
X511917Y-129530D01*
X511699Y-131281D01*
X510826Y-133031D01*
X509515Y-134489D01*
X507987Y-135072D01*
X506241Y-134489D01*
X504712Y-132739D01*
X503839Y-130114D01*
X503621Y-127197D01*
X504057Y-123406D01*
X504712Y-121363D01*
X505804Y-119322D01*
X507332Y-117864D01*
X508861Y-117572D01*
X510389Y-118155D01*
X511481Y-119614D01*
G01X520466Y-131572D02*
X521775Y-133614D01*
X523522Y-134780D01*
X525487Y-135072D01*
X527234Y-134780D01*
X528981Y-133322D01*
X530072Y-131572D01*
X530291Y-129822D01*
X529854Y-127781D01*
X528326Y-126322D01*
X526797Y-125739D01*
X524832D01*
G01X526797D02*
X528107Y-124864D01*
X529199Y-123406D01*
X529636Y-121656D01*
X529199Y-119905D01*
X528107Y-118447D01*
X526142Y-117572D01*
X524177Y-117864D01*
X522212Y-119031D01*
G01X542769Y-135072D02*
Y-117572D01*
X540149Y-121072D01*
G01Y-135072D02*
X545389D01*
G01X560269D02*
X561797Y-134780D01*
X563544Y-133906D01*
X564636Y-132448D01*
X565072Y-130405D01*
X564636Y-128364D01*
X563326Y-126614D01*
X561361Y-125739D01*
X559177D01*
X557867Y-125155D01*
X556775Y-123697D01*
X556339Y-121656D01*
X556994Y-119614D01*
X558522Y-118155D01*
X560269Y-117572D01*
X562015Y-118155D01*
X563544Y-119614D01*
X564199Y-121656D01*
X563762Y-123697D01*
X562671Y-125155D01*
X561361Y-125739D01*
X559177D01*
X557212Y-126614D01*
X555902Y-128364D01*
X555466Y-130405D01*
X555902Y-132448D01*
X556994Y-133906D01*
X558741Y-134780D01*
X560269Y-135072D01*
G01X477152Y-90072D02*
Y-72572D01*
X482392D01*
X484139Y-73447D01*
X485449Y-75489D01*
X485886Y-77822D01*
X485449Y-80155D01*
X484357Y-81905D01*
X482392Y-82781D01*
X477152D01*
G01X503822Y-74031D02*
X502512Y-73155D01*
X500984Y-72572D01*
X499237D01*
X497272Y-73447D01*
X495744Y-74905D01*
X494652Y-76656D01*
X493779Y-79572D01*
X493560Y-82197D01*
X493997Y-84822D01*
X494652Y-86572D01*
X495962Y-88322D01*
X497491Y-89489D01*
X499019Y-90072D01*
X500547D01*
X502076Y-89489D01*
X503386Y-88614D01*
X504478Y-87448D01*
G01X518265Y-80739D02*
X519139Y-79864D01*
X519794Y-78406D01*
X520231Y-76363D01*
X519794Y-74614D01*
X518921Y-73447D01*
X517392Y-72572D01*
X511497D01*
Y-90072D01*
X518702D01*
X520231Y-88906D01*
X521104Y-87155D01*
X521541Y-85114D01*
X521104Y-83072D01*
X519794Y-81322D01*
X518265Y-80739D01*
X511497D01*
G01X527469Y-95905D02*
X540569D01*
G01X546497Y-90072D02*
Y-72572D01*
X556541Y-90072D01*
Y-72572D01*
G01X569019Y-90072D02*
X567272Y-89780D01*
X565744Y-88614D01*
X564434Y-86864D01*
X563560Y-84822D01*
X563124Y-82489D01*
Y-80155D01*
X563560Y-77822D01*
X564434Y-75780D01*
X565744Y-74031D01*
X567272Y-72864D01*
X569019Y-72572D01*
X570765Y-72864D01*
X572294Y-74031D01*
X573604Y-75780D01*
X574478Y-77822D01*
X574914Y-80155D01*
Y-82489D01*
X574478Y-84822D01*
X573604Y-86864D01*
X572294Y-88614D01*
X570765Y-89780D01*
X569019Y-90072D01*
G01X647421Y-120489D02*
X648731Y-118739D01*
X650259Y-117864D01*
X652006Y-117572D01*
X654189Y-118155D01*
X655717Y-119614D01*
X656154Y-121363D01*
X655936Y-123114D01*
X655062Y-124572D01*
X650696Y-127489D01*
X648731Y-129530D01*
X647421Y-132448D01*
X646984Y-135072D01*
X656154D01*
G01X619860Y-72572D02*
X625319Y-90072D01*
X630778Y-72572D01*
G01X647186Y-90072D02*
X638452D01*
Y-72572D01*
X647186D01*
G01X643692Y-81030D02*
X638452D01*
G01X655952Y-90072D02*
Y-72572D01*
X661411D01*
X663157Y-73447D01*
X664249Y-74614D01*
X664686Y-76947D01*
X664249Y-79281D01*
X662939Y-80739D01*
X661411Y-81614D01*
X655952D01*
G01X661411D02*
X664686Y-90072D01*
G01X677819Y-90655D02*
X677382Y-90364D01*
Y-89780D01*
X677819Y-89489D01*
X678256Y-89780D01*
Y-90364D01*
X677819Y-90655D01*
G01X805886Y-117572D02*
Y-135072D01*
X797152D01*
G01X788167Y-127781D02*
X786639Y-125739D01*
X785329Y-124572D01*
X783582Y-123989D01*
X782054Y-124572D01*
X780962Y-125739D01*
X780089Y-127489D01*
X779871Y-129530D01*
X780089Y-131281D01*
X780962Y-133031D01*
X782273Y-134489D01*
X783801Y-135072D01*
X785547Y-134489D01*
X787076Y-132739D01*
X787949Y-130114D01*
X788167Y-127197D01*
X787731Y-123406D01*
X787076Y-121363D01*
X785984Y-119322D01*
X784456Y-117864D01*
X782927Y-117572D01*
X781399Y-118155D01*
X780307Y-119614D01*
G01X753402Y-72572D02*
Y-90072D01*
X762136D01*
G01X779199D02*
Y-78406D01*
G01Y-80447D02*
X778326Y-79281D01*
X777015Y-78697D01*
X775487Y-78406D01*
X773959Y-78989D01*
X772649Y-80155D01*
X771775Y-81905D01*
X771339Y-84239D01*
X771775Y-86572D01*
X772649Y-88322D01*
X773959Y-89489D01*
X775487Y-90072D01*
X777015Y-89780D01*
X778326Y-88906D01*
X779199Y-87739D01*
G01X788184Y-95322D02*
X789494Y-95905D01*
X791241Y-95322D01*
X792332Y-94156D01*
X793206Y-92697D01*
X794515Y-88031D01*
X797354Y-78406D01*
G01X790367D02*
X794515Y-88031D01*
G01X806994Y-82197D02*
X813981D01*
X813326Y-80155D01*
X812234Y-78989D01*
X810706Y-78406D01*
X809177Y-78697D01*
X807867Y-79572D01*
X806994Y-81614D01*
X806557Y-83364D01*
Y-85114D01*
X806994Y-86864D01*
X808086Y-88614D01*
X809396Y-89780D01*
X810924Y-90072D01*
X812452Y-89489D01*
X813981Y-87739D01*
G01X824712Y-90072D02*
Y-78406D01*
G01Y-80739D02*
X825804Y-79572D01*
X826896Y-78697D01*
X828424Y-78406D01*
X829515Y-78697D01*
X830826Y-79572D01*
G01X917819Y-135072D02*
X916072Y-134780D01*
X914544Y-133614D01*
X913234Y-131864D01*
X912360Y-129822D01*
X911924Y-127489D01*
Y-125155D01*
X912360Y-122822D01*
X913234Y-120780D01*
X914544Y-119031D01*
X916072Y-117864D01*
X917819Y-117572D01*
X919565Y-117864D01*
X921094Y-119031D01*
X922404Y-120780D01*
X923278Y-122822D01*
X923714Y-125155D01*
Y-127489D01*
X923278Y-129822D01*
X922404Y-131864D01*
X921094Y-133614D01*
X919565Y-134780D01*
X917819Y-135072D01*
G01X919565Y-130405D02*
X922186Y-135072D01*
G01X930516Y-117572D02*
Y-130114D01*
X931389Y-132739D01*
X933136Y-134489D01*
X935319Y-135072D01*
X937502Y-134489D01*
X939249Y-132739D01*
X940122Y-130114D01*
Y-117572D01*
G01X950199D02*
X955439D01*
G01X952819D02*
Y-135072D01*
G01X950199D02*
X955439D01*
G01X965297D02*
Y-117572D01*
X975341Y-135072D01*
Y-117572D01*
G01X992622Y-119031D02*
X991312Y-118155D01*
X989784Y-117572D01*
X988037D01*
X986072Y-118447D01*
X984544Y-119905D01*
X983452Y-121656D01*
X982579Y-124572D01*
X982360Y-127197D01*
X982797Y-129822D01*
X983452Y-131572D01*
X984762Y-133322D01*
X986291Y-134489D01*
X987819Y-135072D01*
X989347D01*
X990876Y-134489D01*
X992186Y-133614D01*
X993278Y-132448D01*
G01X1005319Y-135072D02*
Y-127197D01*
X1000952Y-117572D01*
G01X1009686D02*
X1005319Y-127197D01*
G01X895516Y-90072D02*
Y-72572D01*
X899882D01*
X901629Y-73447D01*
X902939Y-74614D01*
X904031Y-76363D01*
X904904Y-78406D01*
X905122Y-81322D01*
X904904Y-84239D01*
X904031Y-86281D01*
X902939Y-88031D01*
X901629Y-89197D01*
X899882Y-90072D01*
X895516D01*
G01X914544Y-82197D02*
X921531D01*
X920876Y-80155D01*
X919784Y-78989D01*
X918256Y-78406D01*
X916727Y-78697D01*
X915417Y-79572D01*
X914544Y-81614D01*
X914107Y-83364D01*
Y-85114D01*
X914544Y-86864D01*
X915636Y-88614D01*
X916946Y-89780D01*
X918474Y-90072D01*
X920002Y-89489D01*
X921531Y-87739D01*
G01X932044Y-88031D02*
X933136Y-89197D01*
X934664Y-90072D01*
X935974D01*
X937284Y-89489D01*
X938157Y-88614D01*
X938594Y-87448D01*
X938376Y-85697D01*
X937502Y-84822D01*
X933572Y-83072D01*
X932699Y-81030D01*
X933136Y-79572D01*
X934009Y-78697D01*
X935319Y-78406D01*
X936629Y-78697D01*
X937939Y-79572D01*
G01X952819Y-78406D02*
Y-90072D01*
G01Y-73739D02*
X952382Y-73447D01*
Y-72864D01*
X952819Y-72572D01*
X953256Y-72864D01*
Y-73447D01*
X952819Y-73739D01*
G01X967262Y-94447D02*
X968791Y-95614D01*
X970537Y-95905D01*
X972065Y-95614D01*
X973376Y-94156D01*
X974249Y-92114D01*
Y-78406D01*
G01Y-80739D02*
X973376Y-79572D01*
X972065Y-78697D01*
X970537Y-78406D01*
X968791Y-78989D01*
X967699Y-80155D01*
X966825Y-82197D01*
X966389Y-84239D01*
X966607Y-85989D01*
X967481Y-88031D01*
X968791Y-89489D01*
X970537Y-90072D01*
X971847Y-89780D01*
X973376Y-88614D01*
X974249Y-87448D01*
G01X984107Y-90072D02*
Y-78406D01*
G01Y-81322D02*
X984981Y-79864D01*
X986291Y-78697D01*
X988037Y-78406D01*
X989565Y-78697D01*
X990876Y-79864D01*
X991531Y-81905D01*
Y-90072D01*
G01X1002044Y-82197D02*
X1009031D01*
X1008376Y-80155D01*
X1007284Y-78989D01*
X1005756Y-78406D01*
X1004227Y-78697D01*
X1002917Y-79572D01*
X1002044Y-81614D01*
X1001607Y-83364D01*
Y-85114D01*
X1002044Y-86864D01*
X1003136Y-88614D01*
X1004446Y-89780D01*
X1005974Y-90072D01*
X1007502Y-89489D01*
X1009031Y-87739D01*
G01X1019762Y-90072D02*
Y-78406D01*
G01Y-80739D02*
X1020854Y-79572D01*
X1021946Y-78697D01*
X1023474Y-78406D01*
X1024565Y-78697D01*
X1025876Y-79572D01*
G01X1066519Y-117572D02*
X1064772Y-118155D01*
X1063462Y-119614D01*
X1062589Y-121363D01*
X1061934Y-123697D01*
X1061716Y-126322D01*
X1061934Y-128947D01*
X1062589Y-131281D01*
X1063462Y-133031D01*
X1064772Y-134489D01*
X1066519Y-135072D01*
X1068265Y-134489D01*
X1069576Y-133031D01*
X1070449Y-131281D01*
X1071104Y-128947D01*
X1071322Y-126322D01*
X1071104Y-123697D01*
X1070449Y-121363D01*
X1069576Y-119614D01*
X1068265Y-118155D01*
X1066519Y-117572D01*
G01X1084019Y-135072D02*
X1085547Y-134780D01*
X1087294Y-133906D01*
X1088386Y-132448D01*
X1088822Y-130405D01*
X1088386Y-128364D01*
X1087076Y-126614D01*
X1085111Y-125739D01*
X1082927D01*
X1081617Y-125155D01*
X1080525Y-123697D01*
X1080089Y-121656D01*
X1080744Y-119614D01*
X1082272Y-118155D01*
X1084019Y-117572D01*
X1085765Y-118155D01*
X1087294Y-119614D01*
X1087949Y-121656D01*
X1087512Y-123697D01*
X1086421Y-125155D01*
X1085111Y-125739D01*
X1082927D01*
X1080962Y-126614D01*
X1079652Y-128364D01*
X1079216Y-130405D01*
X1079652Y-132448D01*
X1080744Y-133906D01*
X1082491Y-134780D01*
X1084019Y-135072D01*
G01X1097589Y-135655D02*
X1105449Y-117572D01*
G01X1119019D02*
X1117272Y-118155D01*
X1115962Y-119614D01*
X1115089Y-121363D01*
X1114434Y-123697D01*
X1114216Y-126322D01*
X1114434Y-128947D01*
X1115089Y-131281D01*
X1115962Y-133031D01*
X1117272Y-134489D01*
X1119019Y-135072D01*
X1120765Y-134489D01*
X1122076Y-133031D01*
X1122949Y-131281D01*
X1123604Y-128947D01*
X1123822Y-126322D01*
X1123604Y-123697D01*
X1122949Y-121363D01*
X1122076Y-119614D01*
X1120765Y-118155D01*
X1119019Y-117572D01*
G01X1136082Y-135072D02*
X1136519Y-131281D01*
X1137174Y-128072D01*
X1138047Y-125155D01*
X1139139Y-121947D01*
X1140886Y-117572D01*
X1132152D01*
G01X1150089Y-135655D02*
X1157949Y-117572D01*
G01X1167371Y-120489D02*
X1168681Y-118739D01*
X1170209Y-117864D01*
X1171956Y-117572D01*
X1174139Y-118155D01*
X1175667Y-119614D01*
X1176104Y-121363D01*
X1175886Y-123114D01*
X1175012Y-124572D01*
X1170646Y-127489D01*
X1168681Y-129530D01*
X1167371Y-132448D01*
X1166934Y-135072D01*
X1176104D01*
G01X1189019Y-117572D02*
X1187272Y-118155D01*
X1185962Y-119614D01*
X1185089Y-121363D01*
X1184434Y-123697D01*
X1184216Y-126322D01*
X1184434Y-128947D01*
X1185089Y-131281D01*
X1185962Y-133031D01*
X1187272Y-134489D01*
X1189019Y-135072D01*
X1190765Y-134489D01*
X1192076Y-133031D01*
X1192949Y-131281D01*
X1193604Y-128947D01*
X1193822Y-126322D01*
X1193604Y-123697D01*
X1192949Y-121363D01*
X1192076Y-119614D01*
X1190765Y-118155D01*
X1189019Y-117572D01*
G01X1206519Y-135072D02*
Y-117572D01*
X1203899Y-121072D01*
G01Y-135072D02*
X1209139D01*
G01X1223582D02*
X1224019Y-131281D01*
X1224674Y-128072D01*
X1225547Y-125155D01*
X1226639Y-121947D01*
X1228386Y-117572D01*
X1219652D01*
G01X1114216Y-90072D02*
Y-72572D01*
X1118582D01*
X1120329Y-73447D01*
X1121639Y-74614D01*
X1122731Y-76363D01*
X1123604Y-78406D01*
X1123822Y-81322D01*
X1123604Y-84239D01*
X1122731Y-86281D01*
X1121639Y-88031D01*
X1120329Y-89197D01*
X1118582Y-90072D01*
X1114216D01*
G01X1140449D02*
Y-78406D01*
G01Y-80447D02*
X1139576Y-79281D01*
X1138265Y-78697D01*
X1136737Y-78406D01*
X1135209Y-78989D01*
X1133899Y-80155D01*
X1133025Y-81905D01*
X1132589Y-84239D01*
X1133025Y-86572D01*
X1133899Y-88322D01*
X1135209Y-89489D01*
X1136737Y-90072D01*
X1138265Y-89780D01*
X1139576Y-88906D01*
X1140449Y-87739D01*
G01X1154019Y-72572D02*
Y-90072D01*
G01X1150962Y-78406D02*
X1157076D01*
G01X1168244Y-82197D02*
X1175231D01*
X1174576Y-80155D01*
X1173484Y-78989D01*
X1171956Y-78406D01*
X1170427Y-78697D01*
X1169117Y-79572D01*
X1168244Y-81614D01*
X1167807Y-83364D01*
Y-85114D01*
X1168244Y-86864D01*
X1169336Y-88614D01*
X1170646Y-89780D01*
X1172174Y-90072D01*
X1173702Y-89489D01*
X1175231Y-87739D01*
G54D11*
G01X-13131Y-65072D02*
Y-145072D01*
G01D02*
X1244069D01*
G01X-29131Y-65072D02*
Y-33072D01*
G01X-13131Y-65072D02*
X1244069D01*
G01X-13131Y-100572D02*
X1244069D01*
G01X-17131Y-49072D02*
G02I-12000J0D01*
G01X-22281D02*
G02I-6850J0D01*
G01X-13131D02*
X-45131D01*
G01X31100Y458733D02*
X25576Y464257D01*
Y580226D01*
X76450Y631100D01*
X106293D01*
X106393Y631200D01*
X117000D01*
X119000Y633200D01*
G01X206300Y661100D02*
X200400Y667000D01*
X183500D01*
X169973Y653473D01*
X131651D01*
X120828Y642650D01*
X116350D01*
X108400Y634700D01*
X75100D01*
X28626Y588226D01*
X28625D01*
X22076Y581677D01*
Y461906D01*
X26576Y457406D01*
G01X87683Y698924D02*
X89866Y696741D01*
X145547D01*
X147171Y698365D01*
X155609D01*
X159519Y694455D01*
G01X166600Y513600D02*
X170700D01*
G01X197500Y595700D02*
Y599366D01*
X199543Y601409D01*
Y604641D01*
X202827Y607925D01*
X210332D01*
X212308Y605949D01*
G01X159519Y694455D02*
X160824Y693150D01*
X190027D01*
X191207Y691970D01*
X211145D01*
X214270Y695095D01*
G01X305682Y224074D02*
X304126D01*
X296532Y231668D01*
Y392585D01*
X304335Y400388D01*
X320778D01*
X328747Y408357D01*
Y421245D01*
X321605Y428387D01*
X305693D01*
X291730Y442350D01*
X267250D01*
X263900Y445700D01*
X253800D01*
X251700Y443600D01*
G01X237509Y674915D02*
X243115D01*
X246550Y678350D01*
X265150D01*
X266200Y679400D01*
G01X268384Y662909D02*
X283709D01*
X288700Y667900D01*
G01X311715Y20397D02*
X316912Y15200D01*
X318612D01*
X323219Y10593D01*
X649243D01*
X664799Y26149D01*
X666535D01*
G01X335132Y195874D02*
X334882Y195624D01*
Y168718D01*
X339710Y163890D01*
Y128712D01*
X345603Y122819D01*
X352020D01*
X377096Y97743D01*
X385053D01*
X419423Y63373D01*
X433400D01*
G01X335750Y664700D02*
X334411D01*
X334311Y664600D01*
X317698D01*
X315555Y662457D01*
X303143D01*
X297700Y667900D01*
X288700D01*
G01X383170Y329807D02*
X370660Y342317D01*
Y376194D01*
X372491Y378025D01*
G01X456569Y-65072D02*
Y-145072D01*
G01X596489Y14110D02*
X530850D01*
X526240Y18720D01*
X510675D01*
X508048Y16093D01*
X433230D01*
X428001Y21322D01*
Y25269D01*
G01X486400Y74700D02*
Y75235D01*
X500822Y89657D01*
X517539D01*
X521685Y85511D01*
X534030D01*
X539794Y79747D01*
Y62299D01*
X559290Y42803D01*
X575547D01*
X575550Y42800D01*
G01X594069Y-65072D02*
Y-145072D01*
G01X568430Y50010D02*
X570874Y52454D01*
X598630D01*
X599422Y51662D01*
G01X559600Y47600D02*
X560691Y46509D01*
X607033D01*
X612137Y41405D01*
X721774D01*
X743469Y63100D01*
X771050D01*
X779400Y54750D01*
G01X746500Y47200D02*
X732519D01*
X723224Y37905D01*
X610687D01*
X605792Y42800D01*
X575550D01*
G01X769812Y53660D02*
X766760D01*
X752870Y39770D01*
X736079D01*
X724066Y27757D01*
X680939D01*
X679331Y26149D01*
X666535D01*
G01X618600Y364375D02*
X618650D01*
X617750Y365275D01*
Y365278D01*
X616228Y366800D01*
X616225D01*
X613870Y369155D01*
X610422D01*
X609240Y370337D01*
G01X709069Y-65072D02*
Y-145072D01*
G01X817700Y385700D02*
X809859D01*
X799600Y395959D01*
X732659D01*
X729900Y393200D01*
G01X696000Y508400D02*
X692600Y505000D01*
X674600D01*
X672500Y507100D01*
G01X736803Y52087D02*
X754508D01*
X756431Y54010D01*
G01X762000Y113000D02*
X764700D01*
X769350Y117650D01*
X777927D01*
X779600Y115977D01*
Y105050D01*
X778650Y104100D01*
Y97240D01*
X780150Y95740D01*
Y55500D01*
X779400Y54750D01*
G01X779594Y126865D02*
X780037Y126422D01*
Y121150D01*
X780901D01*
X782950Y119101D01*
Y117790D01*
X783100Y117640D01*
Y115490D01*
X783250Y115340D01*
Y103750D01*
X781250Y101750D01*
G01X781127Y246863D02*
Y247108D01*
X783282Y249263D01*
X788627D01*
X790881Y247009D01*
X796671D01*
X796821Y246859D01*
G01X888668Y322100D02*
X897500Y313268D01*
Y304647D01*
X899569Y302578D01*
Y300422D01*
X897500Y298353D01*
Y201567D01*
X813033Y117100D01*
X803000D01*
G01X857000Y410600D02*
X842600D01*
X817700Y385700D01*
G01X876569Y-65072D02*
Y-145072D01*
G01X1046569Y-65072D02*
Y-145072D01*
G01X1244069Y-65072D02*
Y-145072D01*
G01X1272069Y-49072D02*
G02I-12000J0D01*
G01X1266919D02*
G02I-6850J0D01*
G01X1276069D02*
X1244069D01*
G01X1260069Y-65072D02*
Y-33072D01*
X31100Y458733D03*
X26576Y457406D03*
X41250Y494600D03*
X49600Y496050D03*
X55300Y495600D03*
X74151Y545516D03*
X74498Y551757D03*
X71002Y539219D03*
X74076Y535966D03*
X75508Y542198D03*
X71002Y542368D03*
X67852Y539219D03*
X71002Y545518D03*
Y558117D03*
Y564396D03*
Y561266D03*
X67853Y564416D03*
X75066Y563235D03*
X71002Y554967D03*
X67853D03*
X78276Y545566D03*
X67853Y542368D03*
X71002Y548668D03*
X38550Y617950D03*
X108300Y435900D03*
X118108Y453159D03*
X121826Y453156D03*
X128968Y452741D03*
X125353Y452385D03*
X132109Y451199D03*
X136021Y451394D03*
X127812Y445066D03*
X138000Y485900D03*
X102700Y507100D03*
X114500Y490000D03*
X137050Y476346D03*
X132774Y497000D03*
X86750Y542368D03*
X126337Y554085D03*
X130311Y546700D03*
X127300Y543200D03*
X83600Y573865D03*
X89899Y577014D03*
X86750D03*
X83600Y561265D03*
X133554Y537374D03*
X127401Y606930D03*
X123500Y613100D03*
X93053Y606734D03*
X142447Y611714D03*
X119000Y633200D03*
X120500Y651800D03*
X134650Y612900D03*
X144750Y606350D03*
X141971Y624700D03*
X105600Y597000D03*
X105400Y601300D03*
X104600Y609900D03*
X105600Y605900D03*
X104600Y614000D03*
X104500Y618800D03*
X117050Y602000D03*
X130800Y606700D03*
X106635Y701465D03*
X87683Y698924D03*
X84600Y688000D03*
X197085Y459899D03*
X190278Y459865D03*
X193686Y459799D03*
X176000Y460200D03*
X172200Y460100D03*
X166700Y499800D03*
X166600Y513600D03*
X170700D03*
X146500Y492500D03*
X183300Y493100D03*
X145400Y524046D03*
X176100Y473200D03*
X187167Y513167D03*
X191100Y513367D03*
X154500Y487000D03*
X209800Y478500D03*
X205447Y487762D03*
X170900Y500000D03*
X172100Y467300D03*
X195149Y513751D03*
X150500Y493000D03*
X190950Y482100D03*
X196200Y482600D03*
X200100Y491700D03*
X146216Y486045D03*
X196243Y486782D03*
X159480Y506590D03*
X203610Y529397D03*
X168390Y532060D03*
X149419Y535654D03*
X196249Y630091D03*
X199400Y628646D03*
X151550Y629800D03*
X163200Y610070D03*
X160420Y610170D03*
X184050Y629500D03*
X181176Y627600D03*
X146800Y629900D03*
X204800Y617440D03*
X204642Y621140D03*
X152700Y640800D03*
X163260Y706988D03*
X159519Y694455D03*
X193500Y663000D03*
X206300Y661100D03*
X181300Y679100D03*
X185100Y705600D03*
X184800Y709300D03*
X259000Y453900D03*
X251700Y443600D03*
X224500Y445600D03*
X254900Y453900D03*
X213100Y476300D03*
X261200Y525400D03*
X242500Y523500D03*
X254500Y509600D03*
X213100Y472900D03*
X275200Y474500D03*
X265148Y524595D03*
X228700Y490717D03*
X230700Y486658D03*
X249050Y527150D03*
X249640Y495080D03*
X234700Y490900D03*
X258381Y509498D03*
X225914Y523051D03*
X231800Y512100D03*
X223600Y512400D03*
X213359Y480489D03*
X234943Y565199D03*
X254600Y567700D03*
X260731Y561264D03*
X264333Y528926D03*
X254905Y555761D03*
X258528Y555161D03*
X259100Y567706D03*
X257000Y571700D03*
X223900Y531200D03*
X228100Y545500D03*
X270145Y557526D03*
X261308Y583388D03*
X237100Y590000D03*
X257700Y586400D03*
X261600Y580000D03*
X257600Y576500D03*
X233607Y557671D03*
X254500Y575070D03*
X261100Y571600D03*
X234800Y572000D03*
X248900Y545700D03*
X274623Y578896D03*
X212308Y605949D03*
X243322Y597509D03*
X251314Y598106D03*
X251338Y601506D03*
X258550Y606527D03*
Y610096D03*
X273714Y629870D03*
X245100Y647200D03*
X234205Y598743D03*
X233258Y595693D03*
X253196Y706062D03*
X237509Y674915D03*
X266200Y679400D03*
X268384Y662909D03*
X263700Y723500D03*
X214270Y695095D03*
X217638Y695562D03*
X235000Y692900D03*
X262323Y716917D03*
X311715Y20397D03*
X310353Y62159D03*
X326553Y34687D03*
X338743Y122894D03*
X295841Y176793D03*
X323582Y179064D03*
X299107Y177740D03*
X295462Y173414D03*
X322301Y220009D03*
X305682Y224074D03*
X305882Y234274D03*
X305772Y237673D03*
X321700Y246000D03*
X321600Y250000D03*
X305781Y241076D03*
X334582Y287284D03*
Y283784D03*
X328182Y325174D03*
Y321674D03*
X334582Y312574D03*
Y309074D03*
X328182Y299977D03*
Y296477D03*
X328913Y274414D03*
X334017Y272000D03*
X328182Y375518D03*
Y372018D03*
X334582Y362974D03*
Y359474D03*
Y337771D03*
Y334271D03*
X328182Y350371D03*
Y346871D03*
X316900Y384100D03*
X319679Y387121D03*
X314000Y390500D03*
X335800Y379800D03*
X338800Y435100D03*
X333850Y458400D03*
X276634Y498311D03*
X286797Y516522D03*
X302307Y505799D03*
X298907Y505851D03*
X292100Y516000D03*
X297400Y517981D03*
X325400Y505800D03*
X328200Y511600D03*
X331200Y508900D03*
X299448Y511300D03*
X277603Y479948D03*
X278400Y463300D03*
X280939Y504705D03*
X314400Y505750D03*
X333800Y534830D03*
X329840Y572710D03*
X337550Y534619D03*
X325475Y572818D03*
X334900Y586100D03*
X281610Y590260D03*
X281490Y586862D03*
X337300Y583000D03*
X294107Y560762D03*
X330729Y557268D03*
X298000Y561000D03*
X327059Y557247D03*
X328580Y568120D03*
X320954Y572631D03*
X277048Y590470D03*
X285912Y538750D03*
X318736Y549697D03*
X280100Y532100D03*
X322889Y529380D03*
X322843Y533254D03*
X279664Y535473D03*
X328771Y549035D03*
X332808Y547575D03*
X332834Y543993D03*
X293087Y530571D03*
X325687Y551368D03*
X276839Y582309D03*
X277441Y539882D03*
X308200Y593153D03*
X339751Y616882D03*
Y613185D03*
X335036Y603039D03*
X338733D03*
X325300Y648700D03*
X294500Y630600D03*
X298100Y630650D03*
X330400Y644300D03*
X334700Y644500D03*
X335100Y650600D03*
X338100Y635800D03*
X287200Y632600D03*
X290900Y630900D03*
X278769Y700697D03*
X335750Y664700D03*
X288700Y667900D03*
X340100Y718200D03*
X327250Y701500D03*
X327162Y696776D03*
X282300Y700100D03*
X338669Y691580D03*
X340403Y699400D03*
X340300Y703100D03*
X336200Y677000D03*
X289700Y678830D03*
X280646Y717540D03*
X300100Y670300D03*
X313873Y735907D03*
X314100Y739300D03*
X370870Y45605D03*
X368059Y57759D03*
X354798Y22452D03*
X342539Y120370D03*
X369253Y88733D03*
X367287Y77118D03*
X349206Y129948D03*
X387202Y164664D03*
X387393Y160859D03*
X404727Y162141D03*
X392102Y175384D03*
X392458Y171676D03*
X347482Y254774D03*
X341882Y251064D03*
X342885Y276301D03*
X342958Y279701D03*
X383170Y329807D03*
X383285Y347114D03*
X383327Y343379D03*
X396561Y351418D03*
X346600Y375000D03*
X344732Y386874D03*
X372491Y378025D03*
X342700Y435200D03*
X350491Y453809D03*
X372000Y452100D03*
X369900Y458700D03*
X387450Y454558D03*
X387396Y458126D03*
X384395Y449114D03*
X374700Y460300D03*
X381106Y441241D03*
X374650Y456771D03*
X346500Y435200D03*
X364500Y453700D03*
X367400Y461200D03*
X355400Y453800D03*
X357900Y450800D03*
X363500Y464700D03*
X372000Y477710D03*
X400080Y500854D03*
X355300Y506100D03*
Y513500D03*
X386367Y474700D03*
X400080Y519500D03*
Y491107D03*
Y523903D03*
Y528243D03*
X389349Y480100D03*
X381986Y515631D03*
X374751Y485636D03*
X374715Y498722D03*
X366950Y464700D03*
X390229Y508189D03*
X341500Y520400D03*
X373699Y521160D03*
X387450Y467000D03*
X389288Y483500D03*
X370900Y464700D03*
X378267Y496100D03*
X400093Y536351D03*
X399726Y562327D03*
X399946Y558677D03*
X344163Y553395D03*
X345259Y557566D03*
X391993Y582154D03*
X362300Y555200D03*
X364900Y585171D03*
X364964Y588771D03*
X372939Y559838D03*
X346590Y572090D03*
X350278Y572306D03*
X366270Y563400D03*
X400060Y554743D03*
X393912Y571899D03*
X393910Y575305D03*
X341493Y541250D03*
X393912Y578705D03*
X364014Y593996D03*
X400064Y652598D03*
X396166Y692630D03*
X343200Y667600D03*
X399999Y673422D03*
X396419Y679708D03*
X398983Y706749D03*
X396419Y686586D03*
X372350Y698400D03*
X399093Y703350D03*
X380300Y703000D03*
X399154Y699950D03*
X341900Y690350D03*
X346000Y684300D03*
X383800Y688400D03*
X392800Y677600D03*
X341934Y662794D03*
X388626Y715509D03*
X355298Y711750D03*
X396419Y683186D03*
X469058Y49156D03*
X458972Y49634D03*
X462625Y49881D03*
X430800Y22200D03*
X433600Y19900D03*
X428001Y25269D03*
X433400Y63373D03*
X438600Y91033D03*
X469901Y94047D03*
X461736Y111300D03*
X442800Y90934D03*
X512806Y49494D03*
X473151Y50052D03*
X521200Y57600D03*
X503814Y56676D03*
X515500Y57900D03*
X496430Y22890D03*
X491270Y18877D03*
X485674Y32924D03*
X524950Y16120D03*
X473172Y95508D03*
X479147Y102165D03*
X490100Y111300D03*
X486400Y74700D03*
X513909Y85849D03*
X510408Y85779D03*
X599422Y51662D03*
X568430Y50010D03*
X596489Y14110D03*
X559600Y47600D03*
X575550Y42800D03*
X601311Y13521D03*
X569300Y66274D03*
X596300Y66950D03*
X549550Y61900D03*
X597950Y58950D03*
X564500Y64100D03*
X573600Y49750D03*
X578900Y82500D03*
X551500Y82400D03*
X599682Y103715D03*
X547100Y79900D03*
X666535Y26149D03*
X665800Y7550D03*
X666400Y22200D03*
X634450Y252100D03*
X631550Y249850D03*
X625926Y247530D03*
X627200Y253550D03*
X625250Y264250D03*
X625550Y244150D03*
Y240750D03*
X645516Y225334D03*
X620750Y258050D03*
X642547Y226992D03*
X632958Y231000D03*
X633109Y234397D03*
X632900Y238000D03*
X628300Y230550D03*
X625700Y235750D03*
X640141Y259859D03*
X620160Y203500D03*
X660700Y292200D03*
X634830Y292095D03*
X638453Y291949D03*
X633400Y274600D03*
X652850Y269600D03*
X642300Y276450D03*
X649000Y273500D03*
X652100Y279300D03*
X638603Y296320D03*
X642003Y296249D03*
X645403Y296229D03*
X631069Y292512D03*
X629239Y387969D03*
X620100Y384100D03*
X632220Y389694D03*
X607800Y382362D03*
X618600Y364375D03*
X609240Y370337D03*
X640968Y370425D03*
X606626Y354723D03*
X677770Y196410D03*
X718098Y259423D03*
X718129Y253144D03*
X725466Y200819D03*
X707923Y219765D03*
X708900Y214500D03*
X718111Y224802D03*
X706500Y212150D03*
X709615Y223228D03*
X718111Y231101D03*
X696300Y215750D03*
X702900Y212350D03*
X707679Y233664D03*
X718111Y227952D03*
X722322Y200935D03*
X704279Y226664D03*
X705529Y231064D03*
X705779Y236764D03*
X706079Y240664D03*
X726988Y204312D03*
X718123Y201101D03*
X710079Y203664D03*
X718895Y207125D03*
X705364Y205864D03*
X713168Y207689D03*
X718111Y221653D03*
X692750Y293200D03*
X694307Y283485D03*
X718137Y275186D03*
X702939Y281484D03*
X718109Y268934D03*
X714949Y287814D03*
X729900Y393200D03*
X709006Y410206D03*
X721504Y402321D03*
X691813Y407210D03*
X691874Y410741D03*
X691873Y403800D03*
X720900Y412900D03*
X672500Y507100D03*
X696000Y508400D03*
X715391Y479109D03*
X769812Y53660D03*
X756431Y54010D03*
X736803Y52087D03*
X779400Y54750D03*
X746500Y47200D03*
X776600Y35250D03*
X781250Y101750D03*
X779594Y126865D03*
X762000Y113000D03*
X769500Y91000D03*
X772800Y107550D03*
X776850Y115050D03*
X738160Y199480D03*
X765900Y191900D03*
X764900Y207200D03*
X787402Y240552D03*
X781080Y265763D03*
X784258Y262618D03*
X737009Y240552D03*
X743279Y212196D03*
X781127Y246863D03*
X796821Y246859D03*
X768504Y215355D03*
X763963Y331837D03*
X766437Y329363D03*
X748737Y330263D03*
X784252Y268885D03*
X796839Y290934D03*
X787438Y275197D03*
X796832Y272064D03*
X796875Y304331D03*
X796862Y281522D03*
X784249Y281464D03*
X763081Y350437D03*
X765555Y347963D03*
X775181Y338437D03*
X777655Y335963D03*
X780263Y350737D03*
X782737Y348263D03*
X792163Y338937D03*
X794637Y336463D03*
X746263Y332737D03*
X752363Y343737D03*
X754837Y341263D03*
X790357Y377781D03*
X735300Y401957D03*
X774700Y483600D03*
X736600Y500000D03*
X803000Y117100D03*
X813349Y73142D03*
X809349Y73197D03*
X821962Y189277D03*
X831504Y199129D03*
X840591Y264609D03*
X834791Y258109D03*
X831609Y261291D03*
X834127Y248490D03*
X830945Y251672D03*
X832148Y204444D03*
X816900Y231700D03*
X851591Y310409D03*
X848409Y313591D03*
X856091Y294909D03*
X852909Y298091D03*
X850091Y288909D03*
X846909Y292091D03*
X846591Y270409D03*
X843409Y273591D03*
X844591Y283409D03*
X841409Y286591D03*
X837409Y267791D03*
X822817Y331022D03*
X802363Y336637D03*
X804837Y334163D03*
X820343Y333496D03*
X817700Y385700D03*
X806400Y398700D03*
X810100Y404934D03*
X857000Y410600D03*
X850950Y489300D03*
X883240Y301973D03*
X888668Y322100D03*
X886540Y388996D03*
G54D21*
G01X85984Y549966D02*
X85175Y550775D01*
Y552470D01*
X84253Y553392D01*
X76133D01*
X74498Y551757D01*
G01X76313Y543866D02*
X73836D01*
G02X71813Y544704I0J2861D01*
G01Y544707D01*
X71002Y545518D01*
G01X93242Y559690D02*
X84918D01*
X84568Y559340D01*
Y557680D01*
X84218Y557330D01*
X83518D01*
X83168Y557680D01*
Y559340D01*
X82818Y559690D01*
X75080D01*
X73210Y557820D01*
X71299D01*
X71002Y558117D01*
G01X73954Y569625D02*
X72577Y568248D01*
Y566587D01*
X71002Y565012D01*
Y564396D01*
G01X72833Y570123D02*
X71850Y569140D01*
X70349D01*
X67853Y566644D01*
Y564416D01*
G01X75066Y563235D02*
Y561363D01*
X75485Y560944D01*
X78847D01*
X79286Y561383D01*
Y567835D01*
X79696Y568245D01*
X80276D01*
X80686Y567835D01*
Y566340D01*
X81036Y565990D01*
X91490D01*
G01X71002Y554967D02*
Y555972D01*
X71570Y556540D01*
X73301D01*
X73651Y556190D01*
Y555310D01*
X74001Y554960D01*
X74701D01*
X75051Y555310D01*
Y557920D01*
X75461Y558330D01*
X76041D01*
X76451Y557920D01*
Y555310D01*
X76801Y554960D01*
X77501D01*
X77851Y555310D01*
Y556190D01*
X78884Y557223D01*
Y558510D01*
X79294Y558920D01*
X79874D01*
X80284Y558510D01*
Y556890D01*
X80634Y556540D01*
X88547D01*
G01X88041Y553390D02*
X86067D01*
X85315Y554142D01*
X83597D01*
X83247Y554492D01*
Y555140D01*
X82897Y555490D01*
X82197D01*
X81847Y555140D01*
Y554492D01*
X81497Y554142D01*
X80797D01*
X80447Y554492D01*
Y555140D01*
X80097Y555490D01*
X79397D01*
X79047Y555140D01*
Y554492D01*
X78697Y554142D01*
X73416D01*
X72666Y553392D01*
X69428D01*
X67853Y554967D01*
G01X69743Y537857D02*
X69427Y538173D01*
Y540794D01*
X67853Y542368D01*
G01X83262Y549930D02*
X82950Y550242D01*
X82947D01*
X82695Y550494D01*
X81606D01*
X81256Y550844D01*
Y552054D01*
X80906Y552404D01*
X80206D01*
X79856Y552054D01*
Y550844D01*
X79506Y550494D01*
X78806D01*
X78456Y550844D01*
Y552054D01*
X78106Y552404D01*
X77406D01*
X77056Y552054D01*
Y550844D01*
X75752Y549540D01*
X74319D01*
X71482Y552377D01*
X68954D01*
X68026Y551449D01*
Y549397D01*
X68755Y548668D01*
X71002D01*
G01X92408Y543943D02*
X88325D01*
X86750Y542368D01*
G01X91197Y562840D02*
X85175D01*
X83600Y561265D01*
G01X92076Y540791D02*
X92074Y540793D01*
X85413D01*
X83858Y542348D01*
X82868D01*
X81594Y541074D01*
X81014D01*
X80604Y541484D01*
Y542064D01*
X82046Y543506D01*
Y544086D01*
X81636Y544496D01*
X81056D01*
X79543Y542983D01*
X78963D01*
X78276Y543670D01*
Y545566D01*
G01X176700Y545229D02*
Y547000D01*
X175197Y548503D01*
Y548821D01*
G01X173600Y545182D02*
Y546202D01*
X172658Y547144D01*
X170373D01*
X168898Y545669D01*
G01X700192Y221487D02*
X700263D01*
X702404Y219346D01*
Y219342D01*
X703326Y218420D01*
X706578D01*
X707923Y219765D01*
G01X718111Y224802D02*
X717824Y225089D01*
X714242D01*
X713892Y225439D01*
Y226300D01*
X713542Y226650D01*
X712842D01*
X712492Y226300D01*
Y225439D01*
X712142Y225089D01*
X711442D01*
X711092Y225439D01*
Y226300D01*
X710742Y226650D01*
X710042D01*
X709692Y226300D01*
Y225439D01*
X709342Y225089D01*
X708642D01*
X708292Y225439D01*
Y226300D01*
X707942Y226650D01*
X707242D01*
X706892Y226300D01*
Y225439D01*
X706542Y225089D01*
X703626D01*
X702704Y226011D01*
Y226746D01*
X701550Y227900D01*
X699350D01*
G01X709615Y223228D02*
X703897D01*
X701713Y225412D01*
X700571D01*
X700083Y225900D01*
X699100D01*
G01X702836Y231636D02*
X703954Y230518D01*
Y229846D01*
X705848Y227952D01*
X711083D01*
X711433Y228302D01*
Y229800D01*
X711783Y230150D01*
X712483D01*
X712833Y229800D01*
Y228302D01*
X713183Y227952D01*
X713883D01*
X714233Y228302D01*
Y229800D01*
X714583Y230150D01*
X715283D01*
X715633Y229800D01*
Y228302D01*
X715983Y227952D01*
X718111D01*
G01X705529Y231064D02*
Y231772D01*
X701075Y236226D01*
G01X698500Y223750D02*
X699616D01*
X699804Y223562D01*
X700840D01*
X702749Y221653D01*
X713503D01*
X715100Y223250D01*
X716514D01*
X718111Y221653D01*
G01X719685Y214125D02*
X719686Y214126D01*
Y233598D01*
X719685Y233599D01*
Y234905D01*
X719686Y234906D01*
Y244315D01*
X718742Y245259D01*
X716510D01*
G01X719670Y261730D02*
X719673Y261727D01*
Y257002D01*
X719696Y256979D01*
Y254711D01*
X718129Y253144D01*
G01X738987Y220491D02*
X738583Y220895D01*
Y227299D01*
X738584Y227300D01*
Y238977D01*
X737009Y240552D01*
G54D12*
X197243Y589764D03*
X209842Y583464D03*
X206692Y592913D03*
X200393Y589764D03*
X203542D03*
X165745Y564567D03*
X168895D03*
X165748Y561417D03*
X162598Y558268D03*
X165748Y555118D03*
X168898Y567717D03*
X159449Y570866D03*
X168898Y583464D03*
Y577165D03*
X162598Y586614D03*
X168898D03*
X159449Y577165D03*
X168898Y580315D03*
X162598Y577165D03*
X165748Y580315D03*
Y570866D03*
X162598Y567717D03*
X209842D03*
X162598Y561417D03*
X162595Y564567D03*
X209842D03*
Y561417D03*
Y589763D03*
X206692Y580315D03*
X209841D03*
X159448Y589764D03*
X165749Y542519D03*
X209842Y555119D03*
X175197Y548821D03*
X168898Y545669D03*
X212992Y580315D03*
X212991Y577165D03*
X222441Y548820D03*
X219291D03*
X216141Y589762D03*
X212993Y592912D03*
X212992Y564567D03*
G54D22*
G01X339751Y616882D02*
X340822Y615811D01*
X343728D01*
X346000Y613539D01*
Y600461D01*
X343839Y598300D01*
X333017D01*
X332408Y598909D01*
X327345D01*
X316754Y609500D01*
X299801D01*
X290354Y600053D01*
X273680D01*
X272752Y599125D01*
X252333D01*
X251314Y598106D01*
G01X339751Y613185D02*
X341077Y614511D01*
X343189D01*
X344700Y613000D01*
Y601000D01*
X343300Y599600D01*
X333556D01*
X332947Y600209D01*
X327884D01*
X323940Y604153D01*
Y605143D01*
X322773Y606310D01*
X321783D01*
X320616Y607477D01*
Y608467D01*
X319450Y609633D01*
X318460D01*
X317293Y610800D01*
X313362D01*
X312662Y611500D01*
X311012D01*
X310312Y610800D01*
X308662D01*
X307962Y611500D01*
X306312D01*
X305612Y610800D01*
X303962D01*
X303262Y611500D01*
X301612D01*
X300912Y610800D01*
X299262D01*
X289815Y601353D01*
X288165D01*
X287465Y602053D01*
X285815D01*
X285115Y601353D01*
X283465D01*
X282765Y602053D01*
X281115D01*
X280415Y601353D01*
X273141D01*
X272213Y600425D01*
X252419D01*
X251338Y601506D01*
G01X258550Y606527D02*
X259623Y607600D01*
X261078D01*
X263378Y605300D01*
X284392D01*
X295200Y616108D01*
X303706D01*
X304406Y615408D01*
X306056D01*
X306756Y616108D01*
X308406D01*
X309106Y615408D01*
X310756D01*
X311456Y616108D01*
X313106D01*
X313806Y615408D01*
X315456D01*
X316156Y616108D01*
X317806D01*
X318506Y615408D01*
X320156D01*
X320856Y616108D01*
X323383D01*
X326644Y612847D01*
Y611857D01*
X327811Y610690D01*
X328801D01*
X329968Y609523D01*
Y608533D01*
X331134Y607367D01*
X332124D01*
X333291Y606200D01*
X335250D01*
X336234Y605216D01*
Y604237D01*
X335036Y603039D01*
G01X338733D02*
X337534Y604238D01*
Y605755D01*
X335789Y607500D01*
X333830D01*
X323922Y617408D01*
X294661D01*
X283853Y606600D01*
X263917D01*
X261617Y608900D01*
X259747D01*
X258550Y610096D01*
G01X471260Y145670D02*
Y144304D01*
G02X470520Y143564I-740J0D01*
G01X469820D01*
G03X467067Y140811I0J-2753D01*
G01Y122768D01*
X447342Y103043D01*
X407615D01*
X366609Y130173D01*
X358256Y142659D01*
X350948Y179239D01*
X353346Y191568D01*
X351777Y199635D01*
X355714Y219906D01*
X352678Y235534D01*
X355485Y249707D01*
X349247Y280891D01*
X349248Y280892D01*
X347715Y283191D01*
X345862Y285044D01*
G03X343110Y286184I-2752J-2752D01*
G01X335682D01*
G02X334582Y287284I0J1100D01*
G01X471260Y140158D02*
Y141524D01*
G03X470520Y142264I-740J0D01*
G01X469820D01*
G03X468367Y140811I0J-1453D01*
G01Y122229D01*
X447881Y101743D01*
X407223D01*
X365673Y129232D01*
X361352Y135693D01*
X357031Y142151D01*
X349622Y179236D01*
X352021Y191568D01*
X350452Y199635D01*
X354389Y219906D01*
X351353Y235536D01*
X354159Y249706D01*
X348022Y280384D01*
X346704Y282362D01*
X344942Y284124D01*
G03X343110Y284884I-1833J-1831D01*
G01X335682D01*
G03X334582Y283784I0J-1100D01*
G01X464173Y150394D02*
Y149028D01*
G02X463433Y148288I-740J0D01*
G01X462733D01*
G03X459980Y145535I0J-2753D01*
G01Y120280D01*
X445815Y106115D01*
X410608D01*
X368413Y134034D01*
X361885Y143797D01*
X354735Y179548D01*
X357338Y192939D01*
X356297Y198291D01*
X360220Y218477D01*
X357160Y234223D01*
X359681Y246943D01*
X351447Y288152D01*
X348225Y292976D01*
X343744Y297457D01*
Y297458D01*
G03X340315Y298877I-3428J-3432D01*
G01X329282D01*
G02X328182Y299977I0J1100D01*
G01X464173Y144882D02*
Y146248D01*
G03X463433Y146988I-740J0D01*
G01X462733D01*
G03X461280Y145535I0J-1453D01*
G01Y119741D01*
X446354Y104815D01*
X410216D01*
X367477Y133093D01*
X360660Y143289D01*
X353409Y179544D01*
X356013Y192939D01*
X354972Y198291D01*
X358895Y218477D01*
X355835Y234225D01*
X358355Y246942D01*
X350222Y287644D01*
X347215Y292147D01*
X342825Y296537D01*
G03X340315Y297577I-2511J-2510D01*
G01X329282D01*
G03X328182Y296477I0J-1100D01*
G01X457086Y145670D02*
Y144304D01*
G02X456346Y143564I-740J0D01*
G01X455646D01*
G03X452893Y140811I0J-2753D01*
G01Y119732D01*
X442462Y109301D01*
X412542D01*
X372300Y135937D01*
X368611Y141469D01*
X366766Y144235D01*
X364923Y147000D01*
X358453Y179364D01*
X363385Y204027D01*
X368036Y227285D01*
Y228250D01*
X355438Y291285D01*
X351834Y296693D01*
X343752Y308823D01*
X342247Y310328D01*
G03X339479Y311474I-2768J-2770D01*
G01X335682D01*
G02X334582Y312574I0J1100D01*
G01X457086Y140158D02*
Y141524D01*
G03X456346Y142264I-740J0D01*
G01X455646D01*
G03X454193Y140811I0J-1453D01*
G01Y119193D01*
X443001Y108001D01*
X412150D01*
X405484Y112413D01*
X371363Y134997D01*
X367529Y140748D01*
X365552Y143711D01*
X364763Y144896D01*
X363698Y146493D01*
X357127Y179364D01*
X362110Y204282D01*
X366736Y227414D01*
Y228121D01*
X354213Y290778D01*
X352482Y293376D01*
X350752Y295972D01*
X345412Y303987D01*
X342742Y307993D01*
X341327Y309408D01*
G03X339479Y310174I-1849J-1849D01*
G01X335682D01*
G03X334582Y309074I0J-1100D01*
G01X328182Y325174D02*
G03X329282Y324074I1100J0D01*
G01X338543D01*
G02X341619Y322801I1J-4350D01*
G01X344351Y320069D01*
X356435Y301943D01*
X371222Y228009D01*
Y227216D01*
X361798Y180085D01*
X367934Y149388D01*
X370959Y144814D01*
X374798Y139010D01*
X414981Y112418D01*
X440018D01*
X445807Y118207D01*
Y145535D01*
G02X448560Y148288I2753J0D01*
G01X449260D01*
G03X450000Y149028I0J740D01*
G01Y150394D01*
G01Y144882D02*
Y146248D01*
G03X449260Y146988I-740J0D01*
G01X448560D01*
G03X447107Y145535I0J-1453D01*
G01Y117668D01*
X440557Y111118D01*
X414589D01*
X373859Y138071D01*
X372899Y139523D01*
X371819Y141155D01*
X369874Y144096D01*
X366709Y148883D01*
X360472Y180085D01*
X369922Y227345D01*
Y227880D01*
X355210Y301435D01*
X343340Y319240D01*
X340699Y321881D01*
G03X338543Y322774I-2156J-2157D01*
G01X329282D01*
G03X328182Y321674I0J-1100D01*
G01X334582Y337771D02*
G03X335682Y336671I1100J0D01*
G01X339199D01*
G02X342098Y335471I0J-4102D01*
G01X342650Y334919D01*
X350602Y322988D01*
X358627Y310951D01*
X374840Y229707D01*
X374961Y229103D01*
X365410Y181351D01*
X371100Y152883D01*
X378234Y142181D01*
X398345Y128870D01*
X418458Y115558D01*
X434420D01*
X438720Y119858D01*
Y140811D01*
G02X441473Y143564I2753J0D01*
G01X442173D01*
G03X442913Y144304I0J740D01*
G01Y145670D01*
G01Y140158D02*
Y141524D01*
G03X442173Y142264I-740J0D01*
G01X441473D01*
G03X440020Y140811I0J-1453D01*
G01Y119319D01*
X434959Y114258D01*
X418066D01*
X397627Y127786D01*
X387571Y134442D01*
X377297Y141241D01*
X369875Y152376D01*
X364084Y181351D01*
X373635Y229103D01*
X373565Y229452D01*
X357402Y310444D01*
X353460Y316356D01*
X341639Y334090D01*
X341178Y334551D01*
G03X339199Y335371I-1980J-1981D01*
G01X335682D01*
G03X334582Y334271I0J-1100D01*
G01X435827Y150394D02*
Y149028D01*
G02X435087Y148288I-740J0D01*
G01X434387D01*
G03X431634Y145535I0J-2753D01*
G01Y120373D01*
X429889Y118628D01*
X420198D01*
X382178Y143786D01*
X380017Y147027D01*
X372954Y182351D01*
Y182352D01*
X380631Y220733D01*
X360559Y321107D01*
X343338Y346936D01*
X341842Y348432D01*
G03X339817Y349271I-2025J-2024D01*
G01X329282D01*
G02X328182Y350371I0J1100D01*
G01X435827Y144882D02*
Y146248D01*
G03X435087Y146988I-740J0D01*
G01X434387D01*
G03X432934Y145535I0J-1453D01*
G01Y119834D01*
X430428Y117328D01*
X419806D01*
X381241Y142846D01*
X378792Y146519D01*
X371628Y182351D01*
X371654D01*
Y182352D01*
X371679Y182607D01*
X379305Y220733D01*
X359334Y320599D01*
X342329Y346105D01*
X340922Y347512D01*
G03X339817Y347971I-1106J-1104D01*
G01X329282D01*
G03X328182Y346871I0J-1100D01*
G01X334582Y362974D02*
G03X335682Y361874I1100J0D01*
G01X338598D01*
G02X340915Y360914I0J-3276D01*
G01X341846Y359983D01*
X362327Y329233D01*
X383980Y220982D01*
X376420Y183194D01*
X379695Y166830D01*
X379696D01*
X382969Y150469D01*
X385599Y146563D01*
X420770Y123217D01*
X422584D01*
X424547Y125180D01*
Y140811D01*
G02X427300Y143564I2753J0D01*
G01X428000D01*
G03X428740Y144304I0J740D01*
G01Y145670D01*
G01X334582Y359474D02*
G02X335682Y360574I1100J0D01*
G01X338598D01*
G02X339995Y359994I-1J-1976D01*
G01X340838Y359151D01*
X361102Y328726D01*
X382654Y220982D01*
X375094Y183194D01*
X381745Y149959D01*
X384664Y145622D01*
X402464Y133806D01*
Y133807D01*
X420377Y121917D01*
X423123D01*
X425847Y124641D01*
Y140811D01*
G02X427300Y142264I1453J0D01*
G01X428000D01*
G02X428740Y141524I0J-740D01*
G01Y140158D01*
G01X328182Y375518D02*
Y375387D01*
G03X329132Y374437I950J0D01*
G01X335903D01*
G02X338549Y373342I1J-3741D01*
G01X344217Y367672D01*
X364290Y336017D01*
X387201Y221461D01*
X379886Y184880D01*
X385791Y155332D01*
X388487Y151293D01*
X394600Y145180D01*
X406741D01*
X409849Y148288D01*
X420850D01*
G03X421653Y149091I0J803D01*
G01Y150394D01*
G01X328182Y372018D02*
Y372187D01*
G02X329132Y373137I950J0D01*
G01X335903D01*
G02X337629Y372422I0J-2441D01*
G01X343196Y366854D01*
X363062Y335525D01*
X385875Y221461D01*
X378560Y184881D01*
Y184880D01*
X384566Y154824D01*
X387476Y150464D01*
X393680Y144260D01*
Y144261D01*
X394061Y143880D01*
X407280D01*
X410388Y146988D01*
X420850D01*
G02X421653Y146185I0J-803D01*
G01Y144882D01*
G01X775181Y338437D02*
G03X776733I776J775D01*
G01X777648Y339352D01*
Y339351D01*
X778700Y340403D01*
Y344124D01*
X765020Y357802D01*
X765019D01*
X749786Y360849D01*
X732948Y357480D01*
X720675Y359935D01*
X688091Y353480D01*
X673963Y343951D01*
X666577Y342515D01*
X620329Y311685D01*
X606967Y291639D01*
X598592Y249754D01*
X604324Y221091D01*
X586950Y134218D01*
X573749Y114418D01*
X566964Y107634D01*
X538821D01*
X530846Y115609D01*
Y131663D01*
G02X533310Y134127I2464J0D01*
G01X534189D01*
G03X535039Y134977I0J850D01*
G01Y136221D01*
G01Y130709D02*
Y131977D01*
G03X534189Y132827I-850J0D01*
G01X533310D01*
G03X532146Y131663I0J-1164D01*
G01Y116148D01*
X539360Y108934D01*
X566425D01*
X572738Y115247D01*
X585725Y134726D01*
X586049Y136344D01*
X585499Y137168D01*
X585823Y138786D01*
X586647Y139335D01*
X586970Y140953D01*
X586421Y141776D01*
X586745Y143394D01*
X587569Y143943D01*
X587892Y145561D01*
X587343Y146385D01*
X587667Y148003D01*
X588490Y148552D01*
X588814Y150170D01*
X588265Y150994D01*
X588588Y152612D01*
X589412Y153161D01*
X599311Y202656D01*
X598762Y203480D01*
X599085Y205098D01*
X599909Y205647D01*
X600233Y207265D01*
X599684Y208089D01*
X600007Y209706D01*
X600831Y210256D01*
X601154Y211874D01*
X600605Y212697D01*
X600929Y214315D01*
X601753Y214864D01*
X602076Y216482D01*
X601527Y217306D01*
X601851Y218924D01*
X602674Y219473D01*
X602998Y221091D01*
X597266Y249754D01*
X605742Y292146D01*
X619391Y312623D01*
X666073Y343742D01*
X669765Y344460D01*
Y344461D01*
X673455Y345177D01*
X676988Y347560D01*
X677177Y348532D01*
X678545Y349454D01*
X679517Y349266D01*
X680885Y350188D01*
X681073Y351160D01*
X682441Y352083D01*
X683413Y351894D01*
X687581Y354705D01*
X720676Y361261D01*
X732948Y358806D01*
X749786Y362175D01*
X765660Y359000D01*
X765778Y358883D01*
Y358884D01*
X780000Y344663D01*
Y339864D01*
X777653Y337517D01*
G03X777655Y335963I781J-776D01*
G01X763081Y350437D02*
G03X764637I778J778D01*
G01X765499Y351299D01*
X765500D01*
Y352763D01*
X763359Y354904D01*
X763358D01*
X750215Y357532D01*
X732950Y354079D01*
X720472Y356575D01*
X694492Y351455D01*
X679841Y341572D01*
X668450Y339358D01*
X622744Y308886D01*
X610426Y290410D01*
X602175Y249136D01*
X608068Y219674D01*
X590955Y134122D01*
X583374Y122752D01*
Y122751D01*
X575866Y111488D01*
X568412Y104035D01*
X533704D01*
X523760Y113979D01*
Y126938D01*
G02X526224Y129402I2464J0D01*
G01X527103D01*
G03X527953Y130252I0J850D01*
G01Y131496D01*
G01X765555Y347963D02*
G02Y349515I776J776D01*
G01X766800Y350760D01*
Y353302D01*
X764117Y355985D01*
X763999Y356102D01*
X750215Y358858D01*
X732950Y355405D01*
X720474Y357901D01*
X693983Y352680D01*
X689773Y349840D01*
X688801Y350029D01*
X687433Y349106D01*
X687244Y348134D01*
X685876Y347212D01*
X684904Y347400D01*
X683536Y346478D01*
X683348Y345506D01*
X679333Y342798D01*
X667946Y340585D01*
X621806Y309824D01*
X609201Y290917D01*
X600849Y249136D01*
X606742Y219674D01*
X606418Y218056D01*
X605595Y217507D01*
X605271Y215889D01*
X605820Y215065D01*
X605496Y213447D01*
X604673Y212898D01*
X604349Y211280D01*
X604898Y210457D01*
X604575Y208839D01*
X603751Y208290D01*
X603427Y206672D01*
X603976Y205848D01*
X603653Y204230D01*
X602829Y203681D01*
X602505Y202063D01*
X603054Y201239D01*
X593418Y153065D01*
X592594Y152516D01*
X592270Y150898D01*
X592819Y150074D01*
X592496Y148456D01*
X591672Y147907D01*
X591348Y146289D01*
X591897Y145465D01*
X591574Y143847D01*
X590750Y143298D01*
X590426Y141680D01*
X590976Y140857D01*
X590652Y139239D01*
X589828Y138690D01*
X589505Y137072D01*
X590054Y136248D01*
X589730Y134630D01*
X574855Y112317D01*
X567873Y105335D01*
X534243D01*
X525060Y114518D01*
Y126938D01*
G02X526224Y128102I1164J0D01*
G01X527103D01*
G02X527953Y127252I0J-850D01*
G01Y125985D01*
G01X763963Y331837D02*
G03X765515I776J775D01*
G01X766339Y332661D01*
Y332660D01*
X767797Y334118D01*
Y338864D01*
X755111Y351550D01*
X748056D01*
X669373Y336073D01*
X626336Y307382D01*
X620080Y297999D01*
X620079D01*
X613824Y288616D01*
X605831Y248665D01*
X611885Y218398D01*
X594896Y133445D01*
X579926Y110990D01*
X569612Y100677D01*
X531627D01*
X516673Y115631D01*
Y131663D01*
G02X519137Y134127I2464J0D01*
G01X520016D01*
G03X520866Y134977I0J850D01*
G01Y136221D01*
G01X766437Y329363D02*
G02X766435Y330917I779J778D01*
G01X769097Y333579D01*
Y339403D01*
X755650Y352850D01*
X747929D01*
X694416Y342324D01*
X693594Y342876D01*
X691975Y342558D01*
X691424Y341736D01*
X689805Y341417D01*
X688983Y341969D01*
X687364Y341651D01*
X686812Y340829D01*
X668868Y337299D01*
X625398Y308320D01*
X612599Y289124D01*
X604505Y248665D01*
X610559Y218398D01*
X610235Y216780D01*
X609412Y216231D01*
X609088Y214613D01*
X609637Y213789D01*
X609314Y212171D01*
X608490Y211622D01*
X608167Y210004D01*
X608716Y209181D01*
X608392Y207563D01*
X607568Y207013D01*
X607245Y205395D01*
X607794Y204572D01*
X607470Y202954D01*
X606647Y202405D01*
X606323Y200787D01*
X606872Y199963D01*
X597358Y152388D01*
X596534Y151839D01*
X596210Y150221D01*
X596760Y149397D01*
X596436Y147779D01*
X595612Y147230D01*
X595289Y145612D01*
X595838Y144788D01*
X595514Y143170D01*
X594691Y142621D01*
X594367Y141003D01*
X594916Y140180D01*
X594593Y138562D01*
X593769Y138013D01*
X593445Y136395D01*
X593995Y135571D01*
X593671Y133953D01*
X578915Y111819D01*
X569073Y101977D01*
X532166D01*
X517973Y116170D01*
Y131663D01*
G02X519137Y132827I1164J0D01*
G01X520016D01*
G02X520866Y131977I0J-850D01*
G01Y130709D01*
G01X752363Y343737D02*
G03X753915I776J775D01*
G01X754459Y344281D01*
Y345841D01*
X751800Y348500D01*
X748414D01*
X671129Y333049D01*
X630114Y305706D01*
X623670Y296040D01*
X623669D01*
X617226Y286374D01*
X609581Y245985D01*
X615471Y216527D01*
X598916Y133740D01*
X582160Y108608D01*
X570630Y97079D01*
X526970D01*
X509586Y114463D01*
Y126938D01*
G02X512050Y129402I2464J0D01*
G01X512929D01*
G03X513779Y130252I0J850D01*
G01Y131496D01*
G01X754837Y341263D02*
G02Y342819I778J778D01*
G01X755759Y343742D01*
Y346380D01*
X752339Y349800D01*
X748285D01*
X670622Y334274D01*
X629176Y306644D01*
X615997Y286876D01*
X608256Y245978D01*
X614145Y216527D01*
X613463Y213115D01*
X612639Y212566D01*
X612316Y210948D01*
X612865Y210124D01*
X612541Y208506D01*
X611718Y207957D01*
X611394Y206339D01*
X611943Y205516D01*
X611620Y203898D01*
X610796Y203349D01*
X610472Y201731D01*
X611022Y200907D01*
X610698Y199289D01*
X609874Y198740D01*
X609551Y197122D01*
X610100Y196298D01*
X601378Y152683D01*
X600554Y152134D01*
X600230Y150516D01*
X600780Y149692D01*
X600456Y148074D01*
X599632Y147525D01*
X599309Y145907D01*
X599858Y145083D01*
X599534Y143465D01*
X598711Y142916D01*
X598387Y141298D01*
X598936Y140475D01*
X598613Y138857D01*
X597789Y138308D01*
X597465Y136690D01*
X598015Y135866D01*
X597691Y134248D01*
X581149Y109437D01*
X570091Y98379D01*
X527509D01*
X526342Y99546D01*
Y100536D01*
X525176Y101702D01*
X524186D01*
X523019Y102869D01*
Y103859D01*
X521852Y105026D01*
X520862D01*
X510886Y115002D01*
Y126938D01*
G02X512050Y128102I1164J0D01*
G01X512929D01*
G02X513779Y127252I0J-850D01*
G01Y125985D01*
G01X506693Y136221D02*
Y134977D01*
G02X505843Y134127I-850J0D01*
G01X504964D01*
G03X502500Y131663I0J-2464D01*
G01Y113847D01*
X522567Y93780D01*
X571869D01*
X584447Y106357D01*
X602853Y133967D01*
X618989Y214647D01*
X612840Y245396D01*
X620786Y285131D01*
X632594Y302845D01*
X672909Y329722D01*
X732915Y341723D01*
X746369Y339031D01*
X749462Y335938D01*
Y334383D01*
X747816Y332737D01*
G02X746263I-776J776D01*
G01X748737Y330263D02*
G02Y331819I778J778D01*
G01X750762Y333844D01*
Y336477D01*
X747010Y340229D01*
X732915Y343049D01*
X672401Y330947D01*
X631656Y303783D01*
X619561Y285638D01*
X611565Y245650D01*
X611564D01*
X611514Y245396D01*
X617663Y214647D01*
X617339Y213029D01*
X616516Y212480D01*
X616192Y210862D01*
X616741Y210038D01*
X616418Y208420D01*
X615594Y207871D01*
X615270Y206253D01*
X615819Y205430D01*
X615496Y203812D01*
X614672Y203262D01*
X614349Y201645D01*
X614898Y200821D01*
X614574Y199203D01*
X613750Y198654D01*
X613427Y197036D01*
X613976Y196212D01*
X605315Y152910D01*
X604491Y152361D01*
X604168Y150743D01*
X604717Y149919D01*
X604393Y148301D01*
X603570Y147752D01*
X603246Y146134D01*
X603795Y145310D01*
X603472Y143692D01*
X602648Y143143D01*
X602324Y141525D01*
X602873Y140702D01*
X602550Y139084D01*
X601726Y138535D01*
X601402Y136917D01*
X601952Y136093D01*
X601628Y134475D01*
X583436Y107186D01*
X571330Y95080D01*
X523106D01*
X519230Y98956D01*
Y99946D01*
X518063Y101113D01*
X517073D01*
X515906Y102280D01*
Y103270D01*
X514740Y104436D01*
X513750D01*
X503800Y114386D01*
Y131663D01*
G02X504964Y132827I1164J0D01*
G01X505843D01*
G02X506693Y131977I0J-850D01*
G01Y130709D01*
G01X780263Y350737D02*
G03X781819I778J778D01*
G01X782468Y351386D01*
Y353393D01*
X781450Y354410D01*
X774268Y359198D01*
X729183Y368216D01*
X689400Y360361D01*
X669081Y346655D01*
X664845Y345832D01*
X617205Y314072D01*
X604147Y294525D01*
X595171Y249668D01*
X600436Y223349D01*
X582454Y133440D01*
X570657Y115745D01*
X565725Y110814D01*
X547035D01*
X537933Y119916D01*
Y126938D01*
G02X540397Y129402I2464J0D01*
G01X541276D01*
G03X542126Y130252I0J850D01*
G01Y131496D01*
G01X782737Y348263D02*
G02Y349815I776J776D01*
G01X783226Y350304D01*
X783225D01*
X783768Y350847D01*
Y353932D01*
X782279Y355421D01*
X774775Y360423D01*
X729185Y369542D01*
X688891Y361586D01*
X680819Y356141D01*
X679847Y356330D01*
X678479Y355407D01*
X678290Y354436D01*
X676923Y353513D01*
X675951Y353702D01*
X674583Y352779D01*
X674394Y351807D01*
X668573Y347881D01*
Y347882D01*
X664340Y347059D01*
X616268Y315010D01*
X602922Y295033D01*
X593845Y249668D01*
X599110Y223349D01*
X598786Y221731D01*
X597963Y221182D01*
X597639Y219564D01*
X598188Y218740D01*
X597865Y217122D01*
X597041Y216573D01*
X596717Y214955D01*
X597266Y214132D01*
X596943Y212514D01*
X596119Y211965D01*
X595795Y210347D01*
X596345Y209523D01*
X596021Y207905D01*
X595197Y207356D01*
X594874Y205738D01*
X595423Y204914D01*
X584916Y152383D01*
X584092Y151834D01*
X583769Y150216D01*
X584318Y149392D01*
X583994Y147774D01*
X583171Y147225D01*
X582847Y145607D01*
X583396Y144783D01*
X583073Y143165D01*
X582249Y142616D01*
X581925Y140998D01*
X582474Y140175D01*
X582151Y138557D01*
X581327Y138008D01*
X581003Y136390D01*
X581553Y135566D01*
X581229Y133948D01*
X569646Y116574D01*
X565186Y112114D01*
X547574D01*
X539233Y120455D01*
Y126938D01*
G02X540397Y128102I1164J0D01*
G01X541276D01*
G02X542126Y127252I0J-850D01*
G01Y125985D01*
G01X802363Y336637D02*
G03X803915I776J775D01*
G02X803917Y336640I1960J-1305D01*
G01X804900Y337623D01*
Y350866D01*
X792804Y362955D01*
X729481Y375616D01*
X706195Y371090D01*
X682909Y366563D01*
X610897Y317991D01*
X597195Y297678D01*
X587753Y250433D01*
X592372Y227337D01*
X573942Y132517D01*
X566543Y121419D01*
X562174Y117051D01*
X554410D01*
X552106Y119355D01*
Y126960D01*
G02X554537Y129391I2431J0D01*
G01X555387D01*
G03X556299Y130303I0J912D01*
G01Y131496D01*
G01X804837Y334163D02*
G02Y335720I779J778D01*
G01X805387Y336270D01*
X805386D01*
X806200Y337084D01*
Y351405D01*
X793445Y364153D01*
X761399Y370560D01*
X729485Y376942D01*
X682401Y367789D01*
X638629Y338265D01*
X637657Y338454D01*
X636289Y337531D01*
X636100Y336559D01*
X634733Y335637D01*
X633761Y335826D01*
X632393Y334903D01*
X632204Y333932D01*
X609960Y318928D01*
X595971Y298189D01*
X586427Y250433D01*
X591046Y227333D01*
X590731Y225713D01*
X589910Y225160D01*
X589596Y223540D01*
X590149Y222719D01*
X589834Y221100D01*
X589014Y220546D01*
X588699Y218926D01*
X589253Y218106D01*
X588938Y216486D01*
X588117Y215932D01*
X587802Y214313D01*
X588356Y213492D01*
X588041Y211872D01*
X587220Y211319D01*
X586906Y209699D01*
X587459Y208878D01*
X576302Y151476D01*
X575481Y150922D01*
X575166Y149302D01*
X575720Y148482D01*
X575405Y146862D01*
X574584Y146308D01*
X574270Y144689D01*
X574823Y143868D01*
X574508Y142248D01*
X573688Y141695D01*
X573373Y140075D01*
X573927Y139254D01*
X573612Y137635D01*
X572791Y137081D01*
X572476Y135461D01*
X573030Y134641D01*
X572715Y133021D01*
X565532Y122248D01*
X561635Y118351D01*
X554949D01*
X553406Y119894D01*
Y126960D01*
G02X554537Y128091I1131J0D01*
G01X555387D01*
G02X556299Y127179I0J-912D01*
G01Y125985D01*
G01X792163Y338937D02*
G03X793715I776J775D01*
G02X793717Y338940I1960J-1305D01*
G01X795663Y340886D01*
X795788Y341010D01*
X796382Y341604D01*
Y346412D01*
X787593Y355201D01*
X776651Y362496D01*
X728877Y372048D01*
X685300Y363558D01*
X614229Y316178D01*
X601072Y296450D01*
X591640Y249312D01*
X596460Y225198D01*
X577945Y132630D01*
X568856Y118872D01*
X563974Y113992D01*
X552271D01*
X545019Y121244D01*
Y131684D01*
G02X547450Y134115I2431J0D01*
G01X548300D01*
G03X549212Y135027I0J912D01*
G01Y136221D01*
G01X794637Y336463D02*
G02Y338020I779J779D01*
G01X797682Y341065D01*
Y346951D01*
X788512Y356121D01*
Y356122D01*
X788422Y356212D01*
X787049Y357127D01*
X786855Y358098D01*
X785482Y359013D01*
X784511Y358819D01*
X783138Y359734D01*
X782944Y360705D01*
X781571Y361620D01*
X780601Y361426D01*
X777158Y363721D01*
X728880Y373374D01*
X684795Y364785D01*
X613291Y317116D01*
X599847Y296958D01*
X590314Y249312D01*
X595134Y225198D01*
X593986Y219459D01*
X593162Y218910D01*
X592839Y217292D01*
X593388Y216468D01*
X593064Y214850D01*
X592241Y214301D01*
X591917Y212683D01*
X592466Y211859D01*
X592142Y210241D01*
X591319Y209692D01*
X590995Y208074D01*
X591544Y207251D01*
X591221Y205633D01*
X590397Y205083D01*
X590073Y203466D01*
X590622Y202642D01*
X580481Y151940D01*
X579657Y151391D01*
X579333Y149773D01*
X579882Y148949D01*
X579559Y147331D01*
X578735Y146782D01*
X578411Y145164D01*
X578961Y144341D01*
X578637Y142723D01*
X577813Y142174D01*
X577490Y140556D01*
X578039Y139732D01*
X577715Y138114D01*
X576891Y137565D01*
X576568Y135947D01*
X577117Y135123D01*
X576719Y133135D01*
X567843Y119699D01*
X563435Y115292D01*
X552810D01*
X546319Y121783D01*
Y131684D01*
G02X547450Y132815I1131J0D01*
G01X548300D01*
G02X549212Y131903I0J-912D01*
G01Y130709D01*
G01X820343Y333496D02*
G02X820345Y331942I-779J-778D01*
G01X818403Y330000D01*
X814139D01*
X812964Y331175D01*
X811439Y335282D01*
X813036Y340343D01*
X808889Y357893D01*
X803353Y365939D01*
X799044Y368729D01*
Y368730D01*
X799037Y368734D01*
X729381Y381913D01*
X729369Y381911D01*
Y381910D01*
X679185Y372352D01*
X671262Y366977D01*
X663562Y361754D01*
X648335Y351423D01*
X635952Y347947D01*
X626973Y342516D01*
X622556Y333536D01*
X606117Y323181D01*
X589679Y300370D01*
X579829Y249462D01*
X584211Y223076D01*
X584210D01*
X580265Y205213D01*
X576321Y187350D01*
X570044Y177828D01*
X562796Y171899D01*
X557149D01*
G02X556299Y172749I0J850D01*
G01Y174016D01*
G01Y168504D02*
Y169749D01*
G02X557149Y170599I850J0D01*
G01X563260D01*
X571021Y176946D01*
X577539Y186835D01*
X585535Y223041D01*
X581150Y249444D01*
X586026Y274645D01*
X586027D01*
X590901Y299842D01*
X607025Y322215D01*
X623561Y332631D01*
X627972Y341600D01*
X636474Y346743D01*
X648890Y350228D01*
X679692Y371125D01*
X729382Y380589D01*
X798544Y367504D01*
X802428Y364988D01*
X807679Y357356D01*
X811688Y340393D01*
X810064Y335248D01*
X811844Y330456D01*
X813600Y328700D01*
X818942D01*
X820320Y330078D01*
Y330077D01*
X821265Y331022D01*
G02X822817I776J-775D01*
G54D13*
X353543Y70787D03*
G54D14*
G01X193500Y663000D02*
X185157D01*
X171630Y649473D01*
X135872D01*
X125750Y639351D01*
Y627865D01*
X123060Y625175D01*
X80334D01*
X421653Y144882D03*
X428740Y140158D03*
X435827Y144882D03*
X442913Y140158D03*
X450000Y144882D03*
X457086Y140158D03*
X464173Y144882D03*
X471260Y140158D03*
X421653Y150394D03*
X428740Y145670D03*
X435827Y150394D03*
X442913Y145670D03*
X450000Y150394D03*
X457086Y145670D03*
X464173Y150394D03*
X471260Y145670D03*
X421653Y159055D03*
X506693Y130709D03*
X513779Y125985D03*
X520866Y130709D03*
X527953Y125985D03*
X535039Y130709D03*
X513779Y131496D03*
X527953D03*
X506693Y136221D03*
X520866D03*
X535039D03*
X542126Y125985D03*
X549212Y130709D03*
X556299Y125985D03*
X542126Y131496D03*
X556299D03*
X549212Y136221D03*
X556299Y168504D03*
Y174016D03*
G54D15*
X638780Y114567D03*
X635827Y120079D03*
X629921Y114567D03*
X626969Y120079D03*
X638780Y99606D03*
X635827Y105118D03*
X629921Y99606D03*
X626969Y105118D03*
X717520Y114567D03*
X714567Y120079D03*
X708661Y114567D03*
X705709Y120079D03*
X717520Y99606D03*
X714567Y105118D03*
X708661Y99606D03*
X705709Y105118D03*
G54D16*
X657500Y281500D03*
X648000Y281300D03*
G54D17*
G01X120500Y651800D02*
X113700D01*
X84600Y680900D01*
Y688000D01*
G01X106635Y701465D02*
X108570Y703400D01*
X144155D01*
X147743Y706988D01*
X163260D01*
G01X208250Y585056D02*
X209842Y583464D01*
G01X263700Y723500D02*
X261217Y721017D01*
X260517D01*
X250550Y711050D01*
X238632D01*
X225782Y698200D01*
X199670D01*
X197725Y696255D01*
X195985D01*
X194740Y697500D01*
X172748D01*
X163260Y706988D01*
G01X245100Y647200D02*
X248740D01*
X249340Y647800D01*
X250608D01*
X254265Y651457D01*
X284363D01*
X289030Y646790D01*
X316760D01*
X318615Y644935D01*
X325435D01*
X327850Y647350D01*
X336950D01*
X346940Y657340D01*
X395322D01*
X400064Y652598D01*
G01X340100Y718200D02*
X325900Y732400D01*
X272600D01*
X263700Y723500D01*
G01X326553Y34687D02*
X329440Y31800D01*
X351400D01*
X366920Y16280D01*
X415334D01*
X438954Y39900D01*
X442300D01*
X455700Y53300D01*
Y60836D01*
X487521Y92657D01*
X518782D01*
X522580Y88859D01*
X534925D01*
X542794Y80990D01*
Y64406D01*
X559600Y47600D01*
G01X398983Y706749D02*
X351841D01*
X350540Y708050D01*
X337839D01*
X335489Y705700D01*
X325300D01*
X323960Y704360D01*
Y704050D01*
X317810Y697900D01*
X291090D01*
X288890Y700100D01*
X282300D01*
G01X349206Y129948D02*
X346710Y132444D01*
Y168190D01*
X342859Y172041D01*
Y250087D01*
X341882Y251064D01*
G01X469058Y49156D02*
X471777Y46437D01*
X481313D01*
X483442Y48566D01*
X508217D01*
X509590Y47193D01*
X515923D01*
X521200Y52470D01*
Y57600D01*
G01X490100Y111300D02*
X461736D01*
G01X512806Y49494D02*
X511130Y51170D01*
X474269D01*
X473151Y50052D01*
G01X578900Y82500D02*
X579200Y82800D01*
Y89100D01*
X633000Y142900D01*
X638800D01*
X655600Y159700D01*
X675789D01*
X682939Y166850D01*
X764049D01*
X788058Y190859D01*
X820521D01*
X821962Y189418D01*
Y189277D01*
G01X620160Y203500D02*
X622610D01*
X632610Y193500D01*
X662672D01*
X686822Y169350D01*
X759550D01*
X765900Y175700D01*
Y191900D01*
G01X640968Y370425D02*
X630643Y360100D01*
X612003D01*
X606626Y354723D01*
G01X832148Y204444D02*
X833839Y202753D01*
Y197639D01*
X831838Y195638D01*
X821272D01*
X816521Y200389D01*
X766811D01*
X765000Y202200D01*
Y207100D01*
X764900Y207200D01*
G01X831504Y199129D02*
X823392D01*
X819632Y202889D01*
X774011D01*
X768800Y208100D01*
Y215059D01*
X768504Y215355D01*
G01X774700Y483600D02*
X790570D01*
X796270Y489300D01*
X850950D01*
G54D18*
G01X157875Y552624D02*
X158869Y553618D01*
X163219D01*
X164097Y554496D01*
Y554497D01*
X164099Y554499D01*
Y557597D01*
X164098Y557598D01*
Y559097D01*
X165748Y560747D01*
Y561417D01*
G01Y555118D02*
X164996Y554367D01*
Y553596D01*
X164200Y552800D01*
Y551200D01*
X163400Y550400D01*
X158460D01*
X155343Y547283D01*
G01X638780Y99606D02*
X637776Y101480D01*
X637941Y102021D01*
X639186Y102686D01*
X640630Y104854D01*
X656157Y107960D01*
X692939Y132483D01*
X817814Y157442D01*
X841821Y173445D01*
X845917Y179590D01*
X845918D01*
X850013Y185734D01*
X856702Y219183D01*
X847548Y264952D01*
X843974Y268526D01*
Y270126D01*
X844900Y271052D01*
G02X845948I524J-524D01*
G01X846591Y270409D01*
G01X635827Y105118D02*
X636832Y103242D01*
X637373Y103079D01*
X638354Y103604D01*
X639906Y105934D01*
X644215Y106796D01*
X644804Y107679D01*
X645980Y107914D01*
X646863Y107326D01*
X648040Y107561D01*
X648628Y108444D01*
X649805Y108679D01*
X650687Y108091D01*
X651864Y108326D01*
X652452Y109209D01*
X653629Y109444D01*
X654511Y108856D01*
X655688Y109091D01*
X663176Y114083D01*
X663384Y115123D01*
X664383Y115789D01*
X665423Y115581D01*
X666421Y116247D01*
X666629Y117287D01*
X667628Y117953D01*
X668668Y117745D01*
X679491Y124960D01*
X679699Y126001D01*
X680698Y126666D01*
X681738Y126458D01*
X682736Y127124D01*
X682944Y128164D01*
X683943Y128830D01*
X684983Y128622D01*
X685981Y129287D01*
X686189Y130327D01*
X687188Y130993D01*
X688228Y130785D01*
X689226Y131451D01*
X689434Y132491D01*
X690432Y133156D01*
X691473Y132948D01*
X692471Y133614D01*
X817346Y158573D01*
X840955Y174311D01*
X848882Y186202D01*
X855478Y219183D01*
X846442Y264360D01*
X842774Y268028D01*
Y270624D01*
X844051Y271901D01*
G03Y272949I-524J524D01*
G01X843409Y273591D01*
G01X629921Y99606D02*
X628916Y101481D01*
X629081Y102022D01*
X629434Y102211D01*
X630885Y103662D01*
Y105528D01*
X633752Y108395D01*
X653519Y112347D01*
X687918Y135279D01*
X817677Y161231D01*
X837835Y174693D01*
X846363Y187335D01*
X851904Y215838D01*
X843666Y257034D01*
X838150Y262550D01*
Y264502D01*
X838900Y265252D01*
G02X839948I524J-524D01*
G01X840591Y264609D01*
G01X626969Y105118D02*
X627973Y103243D01*
X628514Y103080D01*
X628712Y103188D01*
X629685Y104160D01*
Y106026D01*
X633160Y109502D01*
X653051Y113478D01*
X654049Y114144D01*
X654258Y115184D01*
X655256Y115849D01*
X656296Y115641D01*
X657295Y116307D01*
X657503Y117347D01*
X658501Y118013D01*
X659541Y117805D01*
X660540Y118470D01*
X660748Y119510D01*
X661746Y120176D01*
X662786Y119968D01*
X663785Y120633D01*
X663993Y121673D01*
X664991Y122339D01*
X666031Y122131D01*
X674470Y127757D01*
X674678Y128797D01*
X675676Y129463D01*
X676716Y129255D01*
X677715Y129920D01*
X677923Y130960D01*
X678921Y131626D01*
X679961Y131418D01*
X680960Y132083D01*
X681168Y133124D01*
X682166Y133789D01*
X683206Y133581D01*
X684205Y134247D01*
X684413Y135287D01*
X685411Y135952D01*
X686452Y135744D01*
X687450Y136410D01*
X817208Y162361D01*
X836972Y175560D01*
X841101Y181681D01*
Y181682D01*
X845231Y187804D01*
X850680Y215835D01*
X846620Y236139D01*
Y236140D01*
X842560Y256442D01*
X836950Y262052D01*
Y265000D01*
X838051Y266101D01*
G03Y267149I-524J524D01*
G01X837409Y267791D01*
G01X638780Y114567D02*
X637776Y116441D01*
X637941Y116982D01*
X637946Y116985D01*
X637952Y116989D01*
X637984Y117005D01*
X637987Y117007D01*
X637996Y117011D01*
X638008Y117017D01*
X638024Y117026D01*
X638029Y117029D01*
X638045Y117039D01*
X638111Y117072D01*
X638457Y117260D01*
X640650Y119454D01*
X641676Y120147D01*
X662749Y124244D01*
X683278Y138091D01*
X814802Y164397D01*
X835662Y178326D01*
X842058Y187807D01*
X847200Y214259D01*
X840439Y248061D01*
X832574Y255926D01*
Y258226D01*
X833100Y258752D01*
G02X834148I524J-524D01*
G01X834791Y258109D01*
G01X635827Y120079D02*
X636832Y118203D01*
X637373Y118040D01*
X637378Y118043D01*
X637384Y118046D01*
X637387Y118048D01*
X637392Y118051D01*
X637398Y118054D01*
X637403Y118057D01*
X637411Y118061D01*
X637418Y118065D01*
X637427Y118070D01*
X637451Y118082D01*
X637460Y118087D01*
X637468Y118091D01*
X637471Y118093D01*
X637476Y118096D01*
X637497Y118107D01*
X637500Y118109D01*
X637550Y118134D01*
X637730Y118232D01*
X639882Y120385D01*
X641207Y121279D01*
X642385Y121508D01*
X642978Y122387D01*
X644156Y122616D01*
X645035Y122023D01*
X646213Y122252D01*
X646806Y123132D01*
X647984Y123361D01*
X648864Y122768D01*
X650042Y122997D01*
X650635Y123876D01*
X651813Y124105D01*
X652692Y123512D01*
X653870Y123741D01*
X654463Y124620D01*
X655641Y124849D01*
X656520Y124256D01*
X662280Y125376D01*
X666640Y128317D01*
X666842Y129358D01*
X667837Y130029D01*
X668878Y129827D01*
X669873Y130498D01*
X670075Y131539D01*
X671070Y132210D01*
X672111Y132007D01*
X673106Y132678D01*
X673309Y133720D01*
X674303Y134391D01*
X675345Y134188D01*
X676340Y134859D01*
X676542Y135900D01*
X677537Y136571D01*
X678578Y136369D01*
X679573Y137040D01*
X679775Y138081D01*
X680770Y138752D01*
X681811Y138550D01*
X682806Y139221D01*
X814333Y165527D01*
X834799Y179193D01*
X840926Y188276D01*
X845976Y214256D01*
X839333Y247469D01*
X831374Y255428D01*
Y258724D01*
X832251Y259601D01*
G03Y260649I-524J524D01*
G01X831609Y261291D01*
G01X629921Y114567D02*
X628916Y116442D01*
X629081Y116983D01*
X629434Y117172D01*
X630685Y118423D01*
Y120500D01*
X634293Y126053D01*
X649630Y136013D01*
X814175Y168831D01*
X833532Y181735D01*
X838455Y189118D01*
X842682Y210275D01*
X836270Y242330D01*
X831700Y246900D01*
Y248396D01*
X832437Y249133D01*
G02X833484I523J-524D01*
G01X834127Y248490D01*
G01X626969Y120079D02*
X627973Y118204D01*
X628514Y118041D01*
X628710Y118147D01*
X629485Y118921D01*
Y120856D01*
X633425Y126921D01*
X649169Y137146D01*
X649170D01*
X654171Y138143D01*
X654759Y139026D01*
X655936Y139260D01*
X656818Y138672D01*
X657995Y138906D01*
X658584Y139788D01*
X659761Y140023D01*
X660643Y139434D01*
X661820Y139669D01*
X662409Y140551D01*
X663586Y140786D01*
X664468Y140197D01*
X729431Y153153D01*
X730020Y154035D01*
X731197Y154270D01*
X732079Y153681D01*
X733256Y153916D01*
X733845Y154798D01*
X735021Y155033D01*
X735904Y154444D01*
X737080Y154679D01*
X737669Y155561D01*
X738846Y155796D01*
X739728Y155207D01*
X799082Y167045D01*
X799671Y167927D01*
X800848Y168162D01*
X801730Y167573D01*
X802907Y167808D01*
X803496Y168690D01*
X804673Y168925D01*
X805555Y168336D01*
X806732Y168571D01*
X807320Y169453D01*
X808497Y169688D01*
X809380Y169099D01*
X813707Y169962D01*
X832666Y182601D01*
X837324Y189586D01*
X841458Y210275D01*
X835164Y241738D01*
X830500Y246402D01*
Y248894D01*
X831588Y249982D01*
X831587D01*
G03Y251030I-524J524D01*
G01X830945Y251672D01*
G01X851591Y310409D02*
X850948Y311052D01*
G03X849900I-524J-524D01*
G01X848724Y309876D01*
Y309076D01*
X857964Y299836D01*
X863659Y291295D01*
X875704Y231079D01*
X865875Y181939D01*
X855707Y166684D01*
X815360Y139787D01*
X751273Y126970D01*
X723058Y108161D01*
X717190Y102293D01*
X717011Y102197D01*
X717008Y102195D01*
X717001Y102191D01*
X716996Y102188D01*
X716681Y102021D01*
X716516Y101480D01*
X717520Y99606D01*
G01X848409Y313591D02*
X849051Y312949D01*
G02Y311901I-524J-524D01*
G01X847524Y310374D01*
Y308578D01*
X857031Y299071D01*
X862528Y290826D01*
X874480Y231079D01*
X864744Y182407D01*
X854841Y167550D01*
X814892Y140918D01*
X813220Y140584D01*
X812337Y141172D01*
X811161Y140937D01*
X810572Y140054D01*
X809396Y139819D01*
X808513Y140407D01*
X807336Y140172D01*
X806748Y139289D01*
X805571Y139054D01*
X804689Y139642D01*
X803512Y139407D01*
X802924Y138525D01*
X801747Y138289D01*
X800864Y138878D01*
X799688Y138642D01*
X799099Y137760D01*
X766102Y131160D01*
X765220Y131749D01*
X764043Y131513D01*
X763454Y130631D01*
X762278Y130396D01*
X761395Y130984D01*
X760219Y130749D01*
X759630Y129866D01*
X758454Y129631D01*
X757571Y130219D01*
X756394Y129984D01*
X755806Y129101D01*
X754629Y128866D01*
X753747Y129454D01*
X752570Y129219D01*
X751982Y128336D01*
X750805Y128101D01*
X722293Y109094D01*
X716466Y103268D01*
X716441Y103254D01*
X716431Y103249D01*
X716116Y103081D01*
X716113Y103079D01*
X715572Y103242D01*
X714567Y105118D01*
G01X708661Y99606D02*
X707657Y101481D01*
X707822Y102022D01*
X708332Y102294D01*
X710600Y104563D01*
Y105902D01*
X714357Y109659D01*
X720398Y110866D01*
X750637Y131025D01*
X815483Y144001D01*
X852712Y168819D01*
X861637Y182205D01*
X870888Y228461D01*
X859547Y285151D01*
X857140Y288760D01*
X853474Y292426D01*
Y294626D01*
X854400Y295552D01*
G02X855448I524J-524D01*
G01X856091Y294909D01*
G01X705709Y105118D02*
X706714Y103243D01*
X707255Y103080D01*
X707608Y103269D01*
X709400Y105061D01*
Y106400D01*
X713765Y110765D01*
X719930Y111997D01*
X750168Y132156D01*
X751345Y132391D01*
X751933Y133274D01*
X753110Y133510D01*
X753992Y132921D01*
X755169Y133157D01*
X755757Y134039D01*
X756934Y134275D01*
X757816Y133687D01*
X758993Y133922D01*
X759581Y134805D01*
X760758Y135040D01*
X761641Y134452D01*
X762817Y134687D01*
X763405Y135570D01*
X764582Y135805D01*
X765465Y135217D01*
X799717Y142071D01*
X800306Y142954D01*
X801482Y143189D01*
X802365Y142601D01*
X803541Y142836D01*
X804130Y143719D01*
X805306Y143954D01*
X806189Y143366D01*
X807366Y143601D01*
X807954Y144484D01*
X809131Y144720D01*
X810013Y144131D01*
X811190Y144367D01*
X811778Y145249D01*
X812955Y145485D01*
X813837Y144897D01*
X815014Y145132D01*
X851846Y169685D01*
X860506Y182674D01*
X869664Y228461D01*
X858416Y284682D01*
X857311Y286339D01*
Y286340D01*
X856207Y287995D01*
X852274Y291928D01*
Y295124D01*
X853551Y296401D01*
G03Y297449I-524J524D01*
G01X852909Y298091D01*
G01X717520Y114567D02*
X716516Y116441D01*
X716681Y116982D01*
X716857Y117076D01*
X716938Y117118D01*
X716945Y117122D01*
X716944Y117123D01*
X716948Y117125D01*
X716953Y117128D01*
X716956Y117130D01*
X717190Y117254D01*
X720249Y120313D01*
X739658Y133252D01*
X816308Y148581D01*
X849375Y170625D01*
X858048Y183633D01*
X866909Y227951D01*
X857764Y273683D01*
X852057Y282243D01*
X847474Y286826D01*
Y288626D01*
X848400Y289552D01*
G02X849448I524J-524D01*
G01X850091Y288909D01*
G01X714567Y120079D02*
X715572Y118203D01*
X716113Y118040D01*
X716116Y118042D01*
X716374Y118180D01*
X716390Y118188D01*
X716445Y118217D01*
X716448Y118219D01*
X716467Y118230D01*
X719484Y121246D01*
X723286Y123781D01*
X723494Y124821D01*
X724493Y125486D01*
X725533Y125278D01*
X739190Y134383D01*
X740367Y134618D01*
X740955Y135501D01*
X742132Y135736D01*
X743014Y135148D01*
X744191Y135383D01*
X744779Y136266D01*
X745956Y136501D01*
X746839Y135913D01*
X748015Y136148D01*
X748604Y137030D01*
X749780Y137266D01*
X750663Y136677D01*
X751840Y136913D01*
X752428Y137795D01*
X753605Y138031D01*
X754487Y137442D01*
X800543Y146653D01*
X801131Y147535D01*
X802308Y147771D01*
X803190Y147182D01*
X804367Y147418D01*
X804956Y148300D01*
X806132Y148535D01*
X807015Y147947D01*
X808191Y148182D01*
X808780Y149065D01*
X809957Y149300D01*
X810839Y148712D01*
X812016Y148947D01*
X812604Y149830D01*
X813781Y150065D01*
X814663Y149477D01*
X815840Y149712D01*
X848509Y171491D01*
X856917Y184102D01*
X865685Y227951D01*
X856633Y273214D01*
X853878Y277346D01*
Y277347D01*
X851124Y281478D01*
X846274Y286328D01*
Y289124D01*
X847551Y290401D01*
G03Y291449I-524J524D01*
G01X846909Y292091D01*
G01X708661Y114567D02*
X707657Y116442D01*
X707822Y116983D01*
X708332Y117255D01*
X709485Y118408D01*
Y119986D01*
X723375Y133876D01*
X816338Y152467D01*
X845747Y172074D01*
X854147Y184674D01*
X862066Y224287D01*
X852781Y270719D01*
X841974Y281526D01*
Y283126D01*
X842900Y284052D01*
G02X843948I524J-524D01*
G01X844591Y283409D01*
G01X705709Y120079D02*
X706714Y118204D01*
X707255Y118041D01*
X707609Y118231D01*
X708285Y118906D01*
Y120484D01*
X711671Y123870D01*
Y124931D01*
X712520Y125780D01*
X713580D01*
X714429Y126628D01*
Y127689D01*
X715277Y128537D01*
X716338D01*
X722783Y134983D01*
X725753Y135576D01*
X726341Y136459D01*
X727518Y136694D01*
X728401Y136106D01*
X729577Y136341D01*
X730166Y137223D01*
X731342Y137459D01*
X732225Y136870D01*
X733402Y137106D01*
X733990Y137988D01*
X735167Y138224D01*
X736049Y137635D01*
X800572Y150539D01*
X801160Y151421D01*
X802337Y151657D01*
X803219Y151068D01*
X804396Y151304D01*
X804985Y152186D01*
X806161Y152421D01*
X807044Y151833D01*
X808220Y152068D01*
X808809Y152951D01*
X809986Y153186D01*
X810868Y152598D01*
X812045Y152833D01*
X812633Y153716D01*
X813810Y153951D01*
X814692Y153363D01*
X815869Y153598D01*
X844881Y172940D01*
X853016Y185142D01*
X860842Y224287D01*
X851675Y270127D01*
X840774Y281028D01*
Y283624D01*
X842051Y284901D01*
G03Y285949I-524J524D01*
G01X841409Y286591D01*
G54D19*
G01X118108Y453159D02*
X115967Y455300D01*
X113700D01*
X106543Y448143D01*
X66142D01*
X47126Y467159D01*
Y502847D01*
X56900Y512621D01*
Y585389D01*
X71911Y600400D01*
X102200D01*
X105600Y597000D01*
G01X121826Y453156D02*
X119770Y451100D01*
X113400D01*
X108943Y446643D01*
X65520D01*
X45626Y466537D01*
Y503469D01*
X50450Y508293D01*
Y581061D01*
X71798Y602409D01*
X104291D01*
X105400Y601300D01*
G01X128968Y452741D02*
X126762Y450535D01*
X124255D01*
X121820Y448100D01*
X114670D01*
X110213Y443643D01*
X64276D01*
X38826Y469093D01*
Y513454D01*
X45950Y520578D01*
Y584250D01*
X71600Y609900D01*
X104600D01*
G01X125353Y452385D02*
X123983D01*
X121198Y449600D01*
X114048D01*
X109591Y445143D01*
X64898D01*
X44126Y465915D01*
Y504091D01*
X48950Y508915D01*
Y582850D01*
X70550Y604450D01*
X104150D01*
X105600Y605900D01*
G01X104600Y614000D02*
X102993Y612393D01*
X70993D01*
X44450Y585850D01*
Y521200D01*
X37326Y514076D01*
Y468471D01*
X63654Y442143D01*
X110935D01*
X115392Y446600D01*
X122442D01*
X124877Y449035D01*
X129945D01*
X132109Y451199D01*
G01X104500Y618800D02*
X99593Y613893D01*
X70371D01*
X39900Y583422D01*
Y518772D01*
X35826Y514698D01*
Y467849D01*
X63032Y440643D01*
X111557D01*
X116014Y445100D01*
X123064D01*
X125499Y447535D01*
X132162D01*
X136021Y451394D01*
G01X152700Y640800D02*
X148317D01*
X146617Y639100D01*
X142290D01*
X140350Y637160D01*
Y637133D01*
X139267Y636050D01*
X139240D01*
X122340Y619150D01*
X109790D01*
X107547Y621393D01*
X91993D01*
X86993Y616393D01*
X68693D01*
X31250Y578950D01*
Y468889D01*
X61996Y438143D01*
X112743D01*
X117200Y442600D01*
X125346D01*
X127812Y445066D01*
G01X41250Y494600D02*
Y509806D01*
X47450Y516006D01*
Y583472D01*
X70712Y606734D01*
X93053D01*
G01X49600Y496050D02*
X51900Y498350D01*
X102600D01*
X112950Y488000D01*
X120800D01*
X133440Y500640D01*
X152287D01*
X158237Y506590D01*
X159480D01*
G01X278400Y463300D02*
X277600Y462500D01*
X274400D01*
X271700Y465200D01*
X216200D01*
X215300Y464300D01*
X200224D01*
X189450Y475074D01*
Y478550D01*
X186500Y481500D01*
X176100D01*
X167600Y473000D01*
X153798D01*
X147998Y478800D01*
X145783D01*
X144983Y479600D01*
X119228D01*
X103866Y494962D01*
X71838D01*
X70750Y496050D01*
X55750D01*
X55300Y495600D01*
G01X74151Y545516D02*
X77095Y548460D01*
X78671D01*
X80721Y546410D01*
X81537D01*
X82295Y547168D01*
X90866D01*
X92591Y545443D01*
X96089D01*
X96166Y545520D01*
X97427D01*
X97927Y546020D01*
Y546990D01*
X98427Y547490D01*
X99427D01*
X99927Y546990D01*
Y546020D01*
X100427Y545520D01*
X101427D01*
X101927Y546020D01*
Y546990D01*
X102427Y547490D01*
X103427D01*
X103927Y546990D01*
Y546020D01*
X104427Y545520D01*
X107039D01*
X116419Y554900D01*
X117374D01*
X117874Y555400D01*
Y556290D01*
X118374Y556790D01*
X119374D01*
X119874Y556290D01*
Y555400D01*
X120374Y554900D01*
X122637D01*
X124278Y556541D01*
X129749D01*
X130249Y556041D01*
Y555880D01*
X130749Y555380D01*
X131749D01*
X132249Y555880D01*
Y556041D01*
X132749Y556541D01*
X133749D01*
X134249Y556041D01*
Y555880D01*
X134749Y555380D01*
X135749D01*
X136249Y555880D01*
Y556041D01*
X136749Y556541D01*
X137749D01*
X138249Y556041D01*
Y555880D01*
X138749Y555380D01*
X139749D01*
X140249Y555880D01*
Y556041D01*
X140749Y556541D01*
X141749D01*
X142249Y556041D01*
Y555880D01*
X142749Y555380D01*
X143749D01*
X144249Y555880D01*
Y556041D01*
X144749Y556541D01*
X145749D01*
X146249Y556041D01*
Y555880D01*
X146749Y555380D01*
X147749D01*
X148249Y555880D01*
Y556041D01*
X148749Y556541D01*
X149570D01*
X152895Y559866D01*
G02X158855Y563183I7912J-7203D01*
G02X159895Y563066I328J-1768D01*
G03X160379Y562966I484J1121D01*
G01X162488D01*
G03X163695Y563466I0J1707D01*
G01X164195Y563966D01*
G02X165745Y564567I1456J-1456D01*
G01X168895D02*
G03X169712Y564566I817J333744D01*
G01X169779D01*
G03X170495Y565282I0J716D01*
G01Y568312D01*
G03X169395Y569267I-1100J-156D01*
G01X165105D01*
G03X164198Y568360I0J-907D01*
G01Y567078D01*
G02X163286Y566166I-912J0D01*
G01X162502D01*
G03X161295Y565666I0J-1707D01*
G01X161095Y565466D01*
G02X160371Y565166I-724J724D01*
G01X154726D01*
G03X152795Y564366I0J-2731D01*
G01X148971Y560542D01*
X142484D01*
X132025Y560541D01*
X126551D01*
X125762Y561330D01*
X117191D01*
X107421Y551560D01*
X89879D01*
X88285Y549966D01*
X85984D01*
G01X71002Y539219D02*
X74713D01*
X83458Y530474D01*
X110158D01*
X116184Y536500D01*
X119571D01*
X122861Y539790D01*
X131930D01*
X132430Y540290D01*
Y542190D01*
X131930Y542690D01*
X130811D01*
X130311Y543190D01*
Y546700D01*
G01X74076Y535966D02*
Y535471D01*
X83073Y526474D01*
X111816D01*
X117842Y532500D01*
X137731D01*
X141656Y536425D01*
X141676D01*
X157875Y552624D01*
G01X75508Y542198D02*
Y541402D01*
X82937Y533973D01*
X84037D01*
X84537Y534473D01*
Y535920D01*
X85037Y536420D01*
X86037D01*
X86537Y535920D01*
Y534473D01*
X87037Y533973D01*
X88037D01*
X88537Y534473D01*
Y535920D01*
X89037Y536420D01*
X90037D01*
X90537Y535920D01*
Y534473D01*
X91037Y533973D01*
X93567D01*
X97114Y537520D01*
X111546D01*
X116176Y542150D01*
X119563D01*
X124313Y546900D01*
X127639D01*
X130037Y549298D01*
X151227D01*
X157863Y555934D01*
G02X159995Y556766I1786J-1428D01*
G03X161633Y557303I289J1886D01*
G01X162598Y558268D01*
G01X127300Y543200D02*
Y542290D01*
X126800Y541790D01*
X122032D01*
X118894Y538652D01*
X115507D01*
X109329Y532474D01*
X106222D01*
X105722Y532974D01*
Y534870D01*
X105222Y535370D01*
X104222D01*
X103722Y534870D01*
Y532974D01*
X103222Y532474D01*
X102222D01*
X101722Y532974D01*
Y534870D01*
X101222Y535370D01*
X100222D01*
X99722Y534870D01*
Y532974D01*
X99222Y532474D01*
X82731D01*
X74789Y540416D01*
X72954D01*
X71002Y542368D01*
G01X155343Y547283D02*
X138560Y530500D01*
X129800D01*
X126664Y527364D01*
X115535D01*
X112645Y524474D01*
X81853D01*
X67852Y538475D01*
Y539219D01*
G01X168898Y567717D02*
X168107Y566926D01*
G03X167295Y564966I1960J-1960D01*
G01Y564190D01*
G02X166995Y563466I-1024J0D01*
G02X165645Y562966I-1350J1573D01*
G03X164706Y562577I0J-1328D01*
G01X164645Y562516D01*
G03X164195Y561430I1085J-1086D01*
G01X164148Y561089D01*
Y560774D01*
X163241Y559867D01*
X162179D01*
X162170Y559866D01*
G03X161530Y559601I0J-905D01*
G01X160327Y558398D01*
G02X159195Y557966I-1580J2441D01*
G03X157569Y557140I453J-2905D01*
G01X157532Y557102D01*
G02X156599Y556552I-1536J1540D01*
G03X155714Y556186I0J-1253D01*
G01X150826Y551298D01*
X129208D01*
X126810Y548900D01*
X123484D01*
X118734Y544150D01*
X114156D01*
X109526Y539520D01*
X95763D01*
X93811Y537568D01*
X82611D01*
X76313Y543866D01*
G01X159449Y570866D02*
X157899Y572416D01*
X154444D01*
X148570Y566542D01*
X135209D01*
X134709Y567042D01*
Y569240D01*
X134209Y569740D01*
X133209D01*
X132709Y569240D01*
Y567042D01*
X132209Y566542D01*
X129394D01*
X128542Y567394D01*
X124675D01*
X124175Y567894D01*
Y571000D01*
X123675Y571500D01*
X122675D01*
X122175Y571000D01*
Y567894D01*
X121675Y567394D01*
X120086D01*
X119560Y567920D01*
Y569500D01*
X119060Y570000D01*
X115350D01*
X112899Y567549D01*
X110621D01*
X101966Y558894D01*
X94038D01*
X93242Y559690D01*
G01X168898Y577165D02*
X169640Y576423D01*
Y575080D01*
X168920Y574360D01*
X167700D01*
X165600Y576460D01*
Y577581D01*
X164466Y578715D01*
X155656D01*
X152882Y581489D01*
X146301D01*
X145310Y580498D01*
X141289D01*
X138071Y583716D01*
X113532D01*
X112466Y582650D01*
X106493D01*
X98587Y574744D01*
Y574522D01*
X94180Y570115D01*
X76599D01*
X76184Y569700D01*
X74029D01*
X73954Y569625D01*
G01X71002Y561266D02*
Y560358D01*
X71430Y559930D01*
X73140D01*
X73650Y560440D01*
Y561770D01*
X73000Y562420D01*
Y564980D01*
X73480Y565460D01*
X74900D01*
X76537Y567097D01*
Y568780D01*
X76972Y569215D01*
X91900D01*
X92760Y568355D01*
Y566880D01*
X93300Y566340D01*
X95410D01*
X95910Y566840D01*
Y568540D01*
X96594Y569224D01*
X98237D01*
X102511Y573498D01*
Y574425D01*
X107736Y579650D01*
X113709D01*
X114775Y580716D01*
X136523D01*
X140549Y576690D01*
X145020D01*
X145490Y576220D01*
Y573100D01*
X146010Y572580D01*
X149300D01*
X150430Y573710D01*
Y575066D01*
X150930Y575566D01*
X158916D01*
X159449Y576099D01*
Y577165D01*
G01X168898Y580315D02*
X167346Y581867D01*
X153933D01*
X152393Y583407D01*
X142623D01*
X138697Y587333D01*
X112906D01*
X111223Y585650D01*
X105250D01*
X95599Y575999D01*
Y572807D01*
X93807Y571015D01*
X76226D01*
X75892Y570681D01*
X73391D01*
X72833Y570123D01*
G01X91490Y565990D02*
X92586Y564894D01*
X98150D01*
X106805Y573549D01*
X110413D01*
X112864Y576000D01*
X114301D01*
X114612Y576310D01*
X116018Y577716D01*
X134946D01*
X139162Y573500D01*
X142770D01*
X144757Y571513D01*
X150782D01*
X153816Y574547D01*
X161620D01*
X162412Y573755D01*
X163293D01*
X164260Y574722D01*
Y576570D01*
X163665Y577165D01*
X162598D01*
G01X88547Y556540D02*
X89579Y555508D01*
X95404D01*
X96789Y556893D01*
X102794D01*
X110431Y564530D01*
X113814D01*
X114678Y565394D01*
X127713D01*
X128565Y564542D01*
X148571D01*
X151395Y567366D01*
G02X155982Y569266I4587J-4587D01*
G01X156032Y569316D01*
X162650D01*
G03X163545Y569616I0J1485D01*
G01X164123Y570194D01*
G02X165745Y570866I1622J-1622D01*
G01X165748D01*
G01X162598Y567717D02*
X162384D01*
G03X161295Y567266I0J-1540D01*
G01X160695Y566666D01*
X160620Y566590D01*
G02X159595Y566166I-1025J1027D01*
G01X154009D01*
G03X151595Y565166I0J-3414D01*
G01X148971Y562542D01*
X130025D01*
Y562541D01*
X127380D01*
X126591Y563330D01*
X116362D01*
X114097Y561065D01*
X113389D01*
X112122Y562332D01*
X111414D01*
X110707Y561625D01*
Y560917D01*
X111974Y559650D01*
Y558942D01*
X111267Y558235D01*
X110559D01*
X109292Y559502D01*
X108584D01*
X107877Y558795D01*
Y558087D01*
X109144Y556820D01*
Y556112D01*
X106592Y553560D01*
X104395D01*
X103952Y554003D01*
X88654D01*
X88041Y553390D01*
G01X133554Y537374D02*
X134265D01*
X135090Y536549D01*
Y535030D01*
X134560Y534500D01*
X131127D01*
X130627Y535000D01*
Y537190D01*
X130127Y537690D01*
X129127D01*
X128627Y537190D01*
Y535000D01*
X128127Y534500D01*
X125550D01*
X125050Y535000D01*
Y536839D01*
X124515Y537374D01*
X123274D01*
X120400Y534500D01*
X117013D01*
X110987Y528474D01*
X83902D01*
X74760Y537616D01*
X72018D01*
X71971Y537569D01*
X70031D01*
X69743Y537857D01*
G01X162595Y564567D02*
G03X161764Y564429I-319J-650D01*
G02X161129Y564166I-635J635D01*
G01X155119D01*
X149494Y558541D01*
X125722D01*
X124933Y559330D01*
X118020D01*
X108250Y549560D01*
X96661D01*
X96167Y549066D01*
X84126D01*
X83262Y549930D01*
G01X38550Y617950D02*
X61150Y640550D01*
X110360D01*
X118210Y648400D01*
X120250D01*
X156209Y684359D01*
X170141D01*
X175400Y679100D01*
X181300D01*
G01X108300Y435900D02*
X108600Y435600D01*
X114000D01*
X118400Y440000D01*
X127900D01*
X133100Y445200D01*
X209800D01*
X211700Y443300D01*
X222200D01*
X224500Y445600D01*
G01X138000Y485900D02*
Y487100D01*
X147900Y497000D01*
X160829D01*
X163508Y494321D01*
X182079D01*
X183300Y493100D01*
G01X149419Y535654D02*
X147132D01*
X139978Y528500D01*
X136800D01*
X134950Y526650D01*
X130550D01*
X111474Y507574D01*
X103174D01*
X102700Y507100D01*
G01X114500Y490000D02*
X119300D01*
X146439Y517139D01*
X210678D01*
X220367Y507450D01*
X256333D01*
X258381Y509498D01*
G01X254900Y453900D02*
X253600Y455200D01*
X220367D01*
X219066Y453899D01*
X187959D01*
X181955Y459903D01*
Y465256D01*
X177511Y469700D01*
X170800D01*
X169000Y471500D01*
X153176D01*
X149588Y475088D01*
X138308D01*
X137050Y476346D01*
G01X132774Y497000D02*
X134874Y499100D01*
X162400D01*
X165179Y496321D01*
X214279D01*
X217812Y492788D01*
X266020D01*
X269232Y496000D01*
X279208D01*
X280850Y497642D01*
Y504616D01*
X280939Y504705D01*
G01X126337Y554085D02*
X125152Y552900D01*
X117248D01*
X107868Y543520D01*
X94577D01*
X94154Y543943D01*
X92408D01*
G01X168898Y583464D02*
X167348Y585014D01*
X161949D01*
X161099Y584164D01*
X155283D01*
X146322Y593125D01*
X142897D01*
X140105Y590333D01*
X111663D01*
X109980Y588650D01*
X102593D01*
X98237Y584294D01*
X96800D01*
X94699Y582193D01*
Y573180D01*
X93434Y571915D01*
X79784D01*
X78870Y572829D01*
Y574407D01*
X79566Y575103D01*
X82362D01*
X83600Y573865D01*
G01X89899Y577014D02*
X89360Y577553D01*
Y584180D01*
X90580Y585400D01*
X94470D01*
X96300Y587230D01*
Y587938D01*
X94803Y589435D01*
Y590298D01*
X96009Y591504D01*
X96978D01*
X98422Y590060D01*
X99130D01*
X100720Y591650D01*
X108737D01*
X110420Y593333D01*
X114077D01*
X114577Y593833D01*
Y595680D01*
X115077Y596180D01*
X117077D01*
X117577Y595680D01*
Y593833D01*
X118077Y593333D01*
X120077D01*
X120577Y593833D01*
Y595680D01*
X121077Y596180D01*
X123077D01*
X123577Y595680D01*
Y593833D01*
X124077Y593333D01*
X126077D01*
X126577Y593833D01*
Y595680D01*
X127077Y596180D01*
X129077D01*
X129577Y595680D01*
Y593833D01*
X130077Y593333D01*
X132077D01*
X132577Y593833D01*
Y595680D01*
X133077Y596180D01*
X135077D01*
X135577Y595680D01*
Y593833D01*
X136077Y593333D01*
X138077D01*
X138577Y593833D01*
Y595680D01*
X139077Y596180D01*
X146907D01*
X154749Y588338D01*
Y585971D01*
X155656Y585064D01*
X160584D01*
X162134Y586614D01*
X162598D01*
G01X86750Y577014D02*
Y577970D01*
X86140Y578580D01*
Y580840D01*
X83270Y583710D01*
Y588370D01*
X84380Y589480D01*
X85420D01*
X85920Y589980D01*
Y592200D01*
X86420Y592700D01*
X88420D01*
X88920Y592200D01*
Y589980D01*
X89420Y589480D01*
X91760D01*
X92480Y590200D01*
Y593990D01*
X93140Y594650D01*
X107494D01*
X112344Y599500D01*
X146422D01*
X157734Y588188D01*
X167324D01*
X168898Y586614D01*
G01X165748Y580315D02*
Y579767D01*
X166787Y578728D01*
X172874D01*
X173595Y578007D01*
Y573015D01*
X173000Y572420D01*
X162210D01*
X161083Y573547D01*
X154225D01*
X150220Y569542D01*
X143200D01*
X142242Y570500D01*
X137919D01*
X137856Y570563D01*
X137632D01*
X133479Y574716D01*
X117261D01*
X116261Y573716D01*
X116260D01*
X115544Y573000D01*
X114107D01*
X111656Y570549D01*
X109378D01*
X100723Y561894D01*
X92143D01*
X91197Y562840D01*
G01X162598Y561417D02*
X162123D01*
G03X161309Y561080I0J-1151D01*
G01X160395Y560166D01*
G02X159954Y559848I-1206J1208D01*
G02X158095Y559966I-828J1652D01*
G03X155109Y559280I-1171J-1743D01*
G01X149127Y553298D01*
X128379D01*
X125981Y550900D01*
X118077D01*
X108697Y541520D01*
X95987D01*
X94836Y540369D01*
X92498D01*
X92076Y540791D01*
G01X325300Y648700D02*
Y649300D01*
X324596Y650004D01*
X289706D01*
X285503Y654207D01*
X253125D01*
X249943Y651025D01*
X236625D01*
X231300Y645700D01*
X225728D01*
X225438Y645410D01*
X225437D01*
X223849Y643822D01*
X218362D01*
X205686Y631146D01*
X198731D01*
X197286Y632591D01*
X194397D01*
X190880Y629074D01*
Y627380D01*
X185484Y621984D01*
X149240D01*
X131556Y604300D01*
X129698D01*
X127401Y606597D01*
Y606930D01*
G01X396166Y692630D02*
X394186Y690650D01*
X391733D01*
X390133Y692250D01*
X386771D01*
X385291Y693730D01*
X375779D01*
X373549Y691500D01*
X361251D01*
X360250Y692501D01*
X348302D01*
X343251Y687450D01*
X333717D01*
X333617Y687550D01*
X289437D01*
X286437Y684550D01*
X276172D01*
X274922Y685800D01*
X233716D01*
X206966Y659050D01*
X192850D01*
X189533Y655733D01*
X183367D01*
X173657Y646023D01*
X162002D01*
X153679Y637700D01*
X149083D01*
X147083Y635700D01*
X142700D01*
X128250Y621250D01*
Y617850D01*
X123500Y613100D01*
G01X142447Y611714D02*
X150493Y619760D01*
X193524D01*
X200284Y613000D01*
X219800D01*
X227900Y621100D01*
X245166D01*
X252766Y628700D01*
X256500D01*
X259721Y631921D01*
X271663D01*
X273714Y629870D01*
G01X335100Y650600D02*
Y651081D01*
X332881Y653300D01*
X326253D01*
X324457Y651504D01*
X290328D01*
X286125Y655707D01*
X252503D01*
X249321Y652525D01*
X224942D01*
X221050Y648633D01*
Y646433D01*
X219967Y645350D01*
X217767D01*
X210777Y638360D01*
Y638359D01*
X205064Y632646D01*
X199353D01*
X197907Y634092D01*
X196665D01*
X196664Y634091D01*
X192459D01*
X188718Y630350D01*
X187133D01*
X186050Y629267D01*
Y628607D01*
X180927Y623484D01*
X146270D01*
X135686Y612900D01*
X134650D01*
G01X141971Y624700D02*
X142300Y625029D01*
Y628330D01*
X150170Y636200D01*
X154301D01*
X162624Y644523D01*
X174279D01*
X183989Y654233D01*
X190155D01*
X193472Y657550D01*
X207588D01*
X234338Y684300D01*
X274300D01*
X275550Y683050D01*
X287059D01*
X290059Y686050D01*
X328521D01*
X332421Y682150D01*
X336063D01*
X337793Y683880D01*
X341121D01*
X341327Y684086D01*
X342286D01*
X348200Y690000D01*
X374171D01*
X374421Y690250D01*
X386649D01*
X388099Y688800D01*
X400840D01*
X401944Y687696D01*
Y185003D01*
X415750Y171197D01*
Y164958D01*
X421653Y159055D01*
G01X117050Y602000D02*
X117550Y602500D01*
X146712D01*
X159448Y589764D01*
G01X396419Y683186D02*
X393836D01*
X391900Y681250D01*
X380572D01*
X378122Y678800D01*
X358328D01*
X355878Y681250D01*
X353500D01*
X352450Y680200D01*
X344991D01*
X344105Y681086D01*
X342571D01*
X342365Y680880D01*
X339037D01*
X337307Y679150D01*
X330673D01*
X326773Y683050D01*
X291303D01*
X288153Y679900D01*
X273800D01*
X266999Y673099D01*
X246121D01*
X242422Y669400D01*
X224783D01*
X209933Y654550D01*
X194716D01*
X191399Y651233D01*
X186883D01*
X171736Y636086D01*
X166695D01*
X162910Y632301D01*
X151434D01*
X149049Y629916D01*
Y629130D01*
X136319Y616400D01*
X134643D01*
X130800Y612557D01*
Y606700D01*
G01X383285Y347114D02*
X385228Y349057D01*
Y358359D01*
X393444Y366575D01*
Y454907D01*
X387655Y460696D01*
X386086D01*
X376082Y470700D01*
X349680D01*
X340700Y461720D01*
Y456900D01*
X327300Y443500D01*
X304600D01*
X294600Y453500D01*
X283900D01*
X281000Y456400D01*
X267971D01*
X263171Y461200D01*
X217880D01*
X216579Y459899D01*
X197085D01*
G01X387450Y454558D02*
X386304D01*
X374262Y466600D01*
X351329D01*
X344700Y459971D01*
Y455242D01*
X328058Y438600D01*
X303400D01*
X293124Y448876D01*
X278424D01*
X275000Y452300D01*
X266413D01*
X261513Y457200D01*
X219538D01*
X218237Y455899D01*
X194244D01*
X190278Y459865D01*
G01X193686Y459799D02*
X195586Y457899D01*
X217408D01*
X218709Y459200D01*
X262342D01*
X267242Y454300D01*
X276600D01*
X279400Y451500D01*
X293500D01*
X303500Y441500D01*
X328129D01*
X342700Y456071D01*
Y460800D01*
X350600Y468700D01*
X375216D01*
X385790Y458126D01*
X387396D01*
G01X346500Y435200D02*
X343500Y432200D01*
X305900D01*
X291224Y446876D01*
X277595D01*
X275171Y449300D01*
X243200D01*
X241500Y451000D01*
X221825D01*
X220724Y449899D01*
X186301D01*
X176000Y460200D01*
G01X172100Y467300D02*
X172700D01*
X178700Y461300D01*
Y460329D01*
X187130Y451899D01*
X219895D01*
X221196Y453200D01*
X252771D01*
X254072Y451899D01*
X255728D01*
X255729Y451900D01*
X257000D01*
X259000Y453900D01*
G01X172200Y460100D02*
X183901Y448399D01*
X241979D01*
X250778Y439600D01*
X290100D01*
X304063Y425637D01*
X320465D01*
X325997Y420105D01*
Y409497D01*
X319638Y403138D01*
X303195D01*
X293782Y393725D01*
Y178852D01*
X295841Y176793D01*
G01X166700Y499800D02*
X170900Y504000D01*
X201330D01*
X204846Y500484D01*
X216174D01*
X219177Y497481D01*
X268810D01*
X269410Y498081D01*
X276404D01*
X276634Y498311D01*
G01X213100Y476300D02*
X208600D01*
X204800Y480100D01*
Y481343D01*
X197293Y488850D01*
X159508D01*
X157206Y491150D01*
X147850D01*
X146500Y492500D01*
G01X254500Y509600D02*
X244050D01*
X240500Y513150D01*
X236200D01*
X232552Y509502D01*
X221144D01*
X211507Y519139D01*
X158661D01*
X156348Y521452D01*
X147994D01*
X145400Y524046D01*
G01X176100Y473200D02*
X176200Y473300D01*
X188395D01*
X199595Y462100D01*
X215951D01*
X217051Y463200D01*
X264000D01*
X268800Y458400D01*
X283100D01*
X286000Y455500D01*
X295699D01*
X305699Y445500D01*
X326429D01*
X338700Y457771D01*
Y462549D01*
X348851Y472700D01*
X377073D01*
X386989Y462784D01*
X388578D01*
X395444Y455918D01*
Y364798D01*
X387427Y356781D01*
Y347479D01*
X383327Y343379D01*
G01X187167Y513167D02*
Y510495D01*
X191354Y506308D01*
X197808D01*
X199750Y508250D01*
X204074D01*
X205474Y506850D01*
X212637D01*
X220006Y499481D01*
X263881D01*
X271168Y506768D01*
X281691D01*
X285458Y503001D01*
X299509D01*
X302307Y505799D01*
G01X191100Y513367D02*
X193529Y510938D01*
Y509391D01*
X194612Y508308D01*
X196500D01*
X199566Y511374D01*
X207401D01*
X209925Y508850D01*
X213466D01*
X220666Y501650D01*
X263150D01*
X271044Y509544D01*
X281744D01*
X285437Y505851D01*
X298907D01*
G01X213100Y472900D02*
X211200Y474800D01*
X207978D01*
X203300Y479478D01*
Y480721D01*
X199221Y484800D01*
X191300D01*
X190250Y485850D01*
X158136D01*
X156986Y487000D01*
X154500D01*
G01X205447Y487762D02*
X208036Y485173D01*
X218518D01*
X219691Y484000D01*
X280243D01*
X292205Y495962D01*
X329938D01*
X340200Y485700D01*
X374687D01*
X374751Y485636D01*
G01X170900Y500000D02*
X172900Y502000D01*
X200501D01*
X204017Y498484D01*
X215345D01*
X218446Y495383D01*
X249337D01*
X249640Y495080D01*
G01X374715Y498722D02*
X370347D01*
X368219Y500850D01*
X353700D01*
X351150Y498300D01*
X341500D01*
X337900Y501900D01*
X333000D01*
X330700Y504200D01*
X329622D01*
X324722Y509100D01*
X312561D01*
X311312Y507851D01*
X286266D01*
X282562Y511555D01*
X270226D01*
X264621Y505950D01*
X219195D01*
X214295Y510850D01*
X211150D01*
X206511Y515489D01*
X196887D01*
X195149Y513751D01*
G01X213359Y480489D02*
X207930D01*
X198069Y490350D01*
X164650D01*
X160000Y495000D01*
X153000D01*
X151000Y493000D01*
X150500D01*
G01X190950Y482100D02*
Y475696D01*
X200846Y465800D01*
X214500D01*
X215400Y466700D01*
X272383D01*
X274883Y464200D01*
X276400D01*
X277800Y465600D01*
X288428D01*
X306528Y447500D01*
X325600D01*
X336700Y458600D01*
Y463378D01*
X348022Y474700D01*
X379750D01*
X387450Y467000D01*
G01X333850Y458400D02*
X332100D01*
X322700Y449000D01*
X307150D01*
X287950Y468200D01*
X215000D01*
X210200Y473000D01*
X202400D01*
X196200Y479200D01*
Y482600D01*
G01X200100Y491700D02*
Y490466D01*
X207128Y483438D01*
X215913D01*
X216851Y482500D01*
X280865D01*
X292827Y494462D01*
X328438D01*
X339400Y483500D01*
X389288D01*
G01X196243Y486782D02*
X193818D01*
X193250Y487350D01*
X158758D01*
X156608Y489500D01*
X149671D01*
X146216Y486045D01*
G01X197243Y589764D02*
X195693Y591314D01*
Y593893D01*
X197500Y595700D01*
G01X197243Y589764D02*
X198800Y591321D01*
Y594400D01*
X197500Y595700D01*
G01X208250Y585056D02*
X205506D01*
G01X208250Y590550D02*
Y585056D01*
G01X198800Y587500D02*
Y585800D01*
G01X201950Y587450D02*
Y585750D01*
G01X205100Y587400D02*
Y585700D01*
G01X286797Y516522D02*
X285338Y517981D01*
X266284D01*
X266282Y517979D01*
X259138D01*
X258867Y518250D01*
X256650D01*
X253400Y521500D01*
X234734D01*
X228834Y527400D01*
X205607D01*
X203610Y529397D01*
G01X261200Y525400D02*
X259900D01*
X255700Y529600D01*
X243490D01*
X241670Y527780D01*
X233010D01*
X227586Y533204D01*
X224824D01*
X224470Y532850D01*
X176180D01*
X175390Y532060D01*
X168390D01*
G01X209842Y561417D02*
X208292Y562967D01*
Y565210D01*
X209201Y566119D01*
X222280D01*
X228999Y559400D01*
X256100D01*
X256953Y558547D01*
X265066D01*
X266087Y557526D01*
X270145D01*
G01X206692Y580315D02*
X207648D01*
X209247Y581914D01*
X210485D01*
X211441Y582870D01*
Y584108D01*
X212348Y585015D01*
X217516D01*
X218531Y584000D01*
X238618D01*
X243138Y579480D01*
X249020D01*
X251470Y581930D01*
X259670D01*
X261600Y580000D01*
G01X165749Y542519D02*
X173757Y534511D01*
X223184D01*
X223723Y535050D01*
X239917D01*
X242817Y532150D01*
X257100D01*
X262512Y526738D01*
X287241D01*
X291074Y530571D01*
X293087D01*
G01X277441Y539882D02*
X272848Y535289D01*
X243922D01*
X239711Y539500D01*
X217600D01*
X215920Y537820D01*
X184002D01*
X176700Y545122D01*
Y545229D01*
G01X341493Y541250D02*
X340386Y540143D01*
X290037D01*
X286756Y536862D01*
X282138D01*
X281500Y537500D01*
X278565D01*
X274854Y533789D01*
X243300D01*
X239278Y537811D01*
X218562D01*
X217671Y536920D01*
X182991D01*
X175840Y544071D01*
X174604D01*
X173600Y545075D01*
Y545182D01*
G01X294500Y630600D02*
X294100Y631000D01*
Y636900D01*
X292250Y638750D01*
X287650D01*
X283510Y642890D01*
X259636D01*
X257156Y640410D01*
X227510D01*
X210300Y623200D01*
X206118D01*
X203818Y625500D01*
X199010D01*
X196249Y628261D01*
Y630091D01*
G01X298100Y630650D02*
Y636900D01*
X291460Y643540D01*
X287683D01*
X285833Y645390D01*
X258600D01*
X256120Y642910D01*
X226473D01*
X225010Y641447D01*
Y641446D01*
X223514Y639950D01*
X218026D01*
X206722Y628646D01*
X199400D01*
G01X151550Y629800D02*
X165600D01*
X169386Y633586D01*
X181052D01*
X184736Y637270D01*
X185870D01*
X187410Y638810D01*
Y643708D01*
X195752Y652050D01*
X212252D01*
X216752Y656550D01*
X218132D01*
X228282Y666700D01*
X254934D01*
X258833Y670599D01*
X286801D01*
X293152Y676950D01*
X311550D01*
X312200Y676300D01*
X320150D01*
X324082Y672368D01*
X331962D01*
X333294Y673700D01*
X337100D01*
X343200Y667600D01*
G01X330400Y644300D02*
X332950Y641750D01*
Y639468D01*
X322014Y628532D01*
X303420D01*
X299445Y624557D01*
X292457D01*
X290794Y626220D01*
X269502D01*
X268039Y627683D01*
Y627684D01*
X267620Y628103D01*
X260786D01*
X256938Y624255D01*
X251455D01*
X246100Y618900D01*
X229100D01*
X222000Y611800D01*
X199100D01*
X195201Y615699D01*
X188841D01*
X181053Y607911D01*
X165359D01*
X163200Y610070D01*
G01X334700Y644500D02*
Y643900D01*
X337500Y641100D01*
Y639218D01*
X325313Y627031D01*
X304041D01*
X299757Y622747D01*
X292145D01*
X290172Y624720D01*
X268820D01*
X264542Y620442D01*
X251342D01*
X247700Y616800D01*
X229900D01*
X223800Y610700D01*
X197810D01*
X194410Y614100D01*
X190128D01*
X182353Y606325D01*
X164265D01*
X160420Y610170D01*
G01X399999Y673422D02*
X396777Y670200D01*
X371600D01*
X364500Y663100D01*
X348629D01*
X341868Y656339D01*
X336542D01*
X334581Y658300D01*
X327429D01*
X326836Y657707D01*
X251674D01*
X248492Y654525D01*
X223942D01*
X218967Y649550D01*
X216733D01*
X213756Y646573D01*
Y644782D01*
X211774Y642800D01*
X200659D01*
X193969Y636110D01*
X191587D01*
X187827Y632350D01*
X186304D01*
X184050Y630096D01*
Y629500D01*
G01X396419Y679708D02*
X394800Y678089D01*
Y676771D01*
X393629Y675600D01*
X379873D01*
X379572Y675299D01*
X357268D01*
X342763Y660794D01*
X327094D01*
X326007Y659707D01*
X238557D01*
X236050Y657200D01*
X222318D01*
X219168Y654050D01*
X218203D01*
X213702Y649549D01*
X208609D01*
X206710Y647650D01*
X202030D01*
X196760Y642380D01*
X193333D01*
X191350Y640397D01*
Y638933D01*
X187186Y634769D01*
X185894D01*
X181176Y630051D01*
Y627600D01*
G01X338100Y635800D02*
X337200D01*
X322487Y621087D01*
X291277D01*
X290191Y620001D01*
X285199D01*
X284180Y621020D01*
X267570D01*
X260917Y614367D01*
X248267D01*
X241500Y607600D01*
X223910D01*
X221935Y609575D01*
X197958D01*
X194983Y606600D01*
X192114D01*
X189864Y604350D01*
X154179D01*
X153792Y603963D01*
X152506D01*
X152119Y604350D01*
X146750D01*
X144750Y606350D01*
G01X396419Y686586D02*
X394432D01*
X390596Y682750D01*
X379950D01*
X377500Y680300D01*
X358950D01*
X356500Y682750D01*
X347279D01*
X346879Y682350D01*
X344963D01*
X344727Y682586D01*
X341949D01*
X341743Y682380D01*
X338415D01*
X336685Y680650D01*
X331799D01*
X327899Y684550D01*
X290681D01*
X287681Y681550D01*
X274350D01*
X273100Y682800D01*
X241504D01*
X236775Y678071D01*
X231332D01*
X209311Y656050D01*
X194094D01*
X190777Y652733D01*
X185333D01*
X175622Y643022D01*
X163405D01*
X155083Y634700D01*
X150792D01*
X147549Y631457D01*
Y630649D01*
X146800Y629900D01*
G01X287200Y632600D02*
X284000D01*
X278210Y638390D01*
X267199D01*
X262928Y634119D01*
X261272D01*
X261271Y634120D01*
X254849D01*
X244209Y623480D01*
X220830D01*
X214701Y617351D01*
X212133D01*
X211985Y617499D01*
X208409D01*
X208350Y617440D01*
X204800D01*
G01X290900Y630900D02*
X290100Y631700D01*
Y633100D01*
X287900Y635300D01*
X284650D01*
X279560Y640390D01*
X266370D01*
X262100Y636120D01*
X255678D01*
X254021Y636121D01*
X243380Y625480D01*
X217931D01*
X213502Y621051D01*
X212133D01*
X211132Y620050D01*
X205732D01*
X204642Y621140D01*
G01X185100Y705600D02*
X190250Y700450D01*
X224850D01*
X237700Y713300D01*
X249600D01*
X260300Y724000D01*
Y733800D01*
X269900Y743400D01*
X290300D01*
X297200Y736500D01*
X313280D01*
X313873Y735907D01*
G01X184800Y709300D02*
X191650Y702450D01*
X224021D01*
X236871Y715300D01*
X248771D01*
X258300Y724829D01*
Y734629D01*
X269071Y745400D01*
X291129D01*
X298029Y738500D01*
X313300D01*
X314100Y739300D01*
G01X213100Y476300D02*
X216553Y472847D01*
X267608D01*
X271112Y476350D01*
X277550D01*
X281300Y472600D01*
X285780D01*
X306880Y451500D01*
X322700D01*
X351300Y480100D01*
X366800D01*
X369190Y477710D01*
X372000D01*
G01X400080Y500854D02*
X395374Y505560D01*
X366776D01*
X356236Y516100D01*
X341556D01*
X341254Y516402D01*
X338476D01*
X333617Y521261D01*
X315424D01*
X313105Y523580D01*
X292586D01*
X288487Y519481D01*
X265662D01*
X265661Y519480D01*
X264419D01*
X264418Y519481D01*
X259758D01*
X259489Y519750D01*
X257450D01*
X253700Y523500D01*
X242500D01*
G01X275200Y474500D02*
X271384D01*
X267891Y471007D01*
X267085Y470200D01*
X215800D01*
X213100Y472900D01*
G01X265148Y524595D02*
X287235D01*
X290720Y528080D01*
X314971D01*
X317290Y525761D01*
X329586D01*
X332998Y529173D01*
X344409D01*
X344730Y529494D01*
X373483D01*
X383477Y519500D01*
X400080D01*
G01X228700Y490717D02*
X231386D01*
X234303Y487800D01*
X279799D01*
X291500Y499501D01*
X331155D01*
X336956Y493700D01*
X397487D01*
X400080Y491107D01*
G01X230700Y486658D02*
X231858Y485500D01*
X279621D01*
X292122Y498001D01*
X330099D01*
X338500Y489600D01*
X386581D01*
X400444Y475737D01*
Y355301D01*
X396561Y351418D01*
G01X209800Y478500D02*
X215200D01*
X217354Y476346D01*
X268985D01*
X270489Y477850D01*
X270491Y477851D01*
X271733D01*
X271734Y477850D01*
X283303D01*
X298415Y492962D01*
X326296D01*
X337558Y481700D01*
X368400D01*
X370529Y479571D01*
X383242D01*
X383771Y480100D01*
X389349D01*
G01X249050Y527150D02*
X254294D01*
X258694Y522750D01*
X260733D01*
X261002Y522481D01*
X287243D01*
X291342Y526580D01*
X314349D01*
X316668Y524261D01*
X362882D01*
X363733Y523410D01*
X365267D01*
X365278Y523421D01*
X369488D01*
X370328Y524261D01*
X374731D01*
X382153Y516839D01*
Y515798D01*
X381986Y515631D01*
G01X325400Y505800D02*
X323600Y507600D01*
X313533D01*
X306934Y501001D01*
X290500D01*
X282499Y493000D01*
X271000D01*
X268900Y490900D01*
X234700D01*
G01X223900Y531200D02*
X227877D01*
X233727Y525350D01*
X248233D01*
X248283Y525300D01*
X254022D01*
X258072Y521250D01*
X260111D01*
X260380Y520981D01*
X287865D01*
X291964Y525080D01*
X313727D01*
X316046Y522761D01*
X334239D01*
X339098Y517902D01*
X341876D01*
X342178Y517600D01*
X355622D01*
X355924Y517902D01*
X370826D01*
X380295Y508433D01*
X389985D01*
X390229Y508189D01*
G01X328200Y511600D02*
X327700Y512100D01*
X311317D01*
X310167Y510950D01*
X302514D01*
X300314Y513150D01*
X287570D01*
X286048Y514672D01*
X286030D01*
X284338Y516364D01*
X261783D01*
X259767Y514348D01*
X256852D01*
X251200Y520000D01*
X229400D01*
X226349Y523051D01*
X225914D01*
G01X331200Y508900D02*
X330994Y509106D01*
X326838D01*
X325344Y510600D01*
X311939D01*
X310789Y509450D01*
X286789D01*
X283089Y513150D01*
X262813D01*
X261011Y511348D01*
X255581D01*
X253779Y513150D01*
X243329D01*
X241329Y515150D01*
X234850D01*
X231800Y512100D01*
G01X299448Y511300D02*
X287280D01*
X283930Y514650D01*
X262191D01*
X260389Y512848D01*
X256204D01*
X254402Y514650D01*
X243951D01*
X241951Y516650D01*
X228044D01*
X223794Y512400D01*
X223600D01*
G01X277603Y479948D02*
X277513Y480038D01*
X270555D01*
X269517Y479000D01*
X269516D01*
X268602Y478085D01*
X268567Y478050D01*
X218009D01*
X215520Y480539D01*
X213409D01*
X213359Y480489D01*
G01X234943Y565199D02*
Y566700D01*
X234198Y567445D01*
X229456D01*
X221286Y575615D01*
X212348D01*
X211441Y576522D01*
Y578764D01*
X212992Y580315D01*
G01X254600Y567700D02*
X252880Y569420D01*
X237371D01*
X237291Y569500D01*
X231066D01*
X221851Y578715D01*
X214655D01*
X213105Y577165D01*
X212991D01*
G01X260731Y561264D02*
X260218Y561777D01*
X232962D01*
X232379Y561194D01*
X229282D01*
X221208Y569268D01*
X211393D01*
X209842Y567717D01*
G01X264333Y528926D02*
X265021Y528238D01*
X286619D01*
X290824Y532443D01*
X306458D01*
X309306Y529595D01*
X316174D01*
X318508Y527261D01*
X328823D01*
X331936Y530374D01*
Y535583D01*
X334064Y537711D01*
X367159D01*
X371892Y542444D01*
X394000D01*
X400093Y536351D01*
G01X330729Y557268D02*
X330203D01*
X326335Y553400D01*
X323619D01*
X321855Y551636D01*
X315221D01*
X312131Y554726D01*
X296348D01*
X294866Y553244D01*
X268424D01*
X267879Y552699D01*
X257454D01*
X254905Y555248D01*
Y555761D01*
G01X327059Y557247D02*
X325242Y555430D01*
X322820D01*
X321026Y553636D01*
X316468D01*
X313138Y556966D01*
X295606D01*
X293940Y555300D01*
X265484D01*
X264237Y556547D01*
X259914D01*
X258528Y555161D01*
G01X259100Y567706D02*
X259336D01*
X259429Y567613D01*
X264460D01*
X266316Y569469D01*
X287515D01*
X288275Y568709D01*
X294081D01*
X295787Y570415D01*
X325049D01*
X327124Y568340D01*
X327289D01*
X327509Y568120D01*
X328580D01*
G01X320954Y572631D02*
X320925Y572660D01*
X288584D01*
X287893Y571969D01*
X265378D01*
X263115Y569706D01*
X258994D01*
X257000Y571700D01*
G01X209842Y564567D02*
X211442Y562967D01*
X213635D01*
X214591Y562011D01*
Y560776D01*
X215548Y559819D01*
X222280D01*
X226278Y555821D01*
X245278D01*
X249383Y551716D01*
X255608D01*
X256626Y550698D01*
X258282D01*
X266099Y550699D01*
X268709D01*
X269254Y551244D01*
X296433D01*
X297800Y552611D01*
X308777D01*
X311752Y549636D01*
X318675D01*
X318736Y549697D01*
G01X328771Y549035D02*
X328524Y549282D01*
X322052D01*
X320051Y547281D01*
X302719D01*
X301243Y548757D01*
X299709D01*
X298352Y547400D01*
X260702D01*
X256915Y543613D01*
X243865D01*
X242267Y545211D01*
X233996D01*
X230387Y548820D01*
X222441D01*
G01X219291D02*
X219880D01*
X221430Y547270D01*
X229815D01*
X233374Y543711D01*
X241645D01*
X243243Y542113D01*
X257537D01*
X261324Y545900D01*
X288600D01*
X289857Y544643D01*
X305292D01*
X306199Y545550D01*
X330783D01*
X332808Y547575D01*
G01X364964Y588771D02*
X362094D01*
X360865Y590000D01*
X345512D01*
X342760Y592752D01*
X330750D01*
X330118Y593384D01*
X316475D01*
X313049Y596810D01*
X305812D01*
X303530Y594528D01*
X278131D01*
X276803Y593200D01*
X261153D01*
X260003Y592050D01*
X243062D01*
X239419Y595693D01*
X233258D01*
G01X228100Y545500D02*
X229463D01*
X232752Y542211D01*
X241023D01*
X242621Y540613D01*
X262069D01*
X265856Y544400D01*
X287978D01*
X289235Y543143D01*
X305914D01*
X306764Y543993D01*
X332834D01*
G01X372939Y559838D02*
X364260D01*
X363648Y560450D01*
X353454D01*
X352554Y559550D01*
X342192D01*
X338442Y563300D01*
X321259D01*
X320296Y564263D01*
X293320D01*
X291526Y562469D01*
X280932D01*
X275989Y557526D01*
X270145D01*
G01X216141Y589762D02*
X219903Y586000D01*
X240283D01*
X241913Y584370D01*
X249040D01*
X249360Y584050D01*
X250511D01*
X250631Y583930D01*
X260766D01*
X261308Y583388D01*
G01X212993Y592912D02*
X225188D01*
X228100Y590000D01*
X237100D01*
G01X257700Y586400D02*
X255490Y588610D01*
X249690D01*
X248199Y587119D01*
X243189D01*
X242308Y588000D01*
X224800D01*
X221486Y591314D01*
X211393D01*
X209842Y589763D01*
G01X257600Y576500D02*
X256450Y577650D01*
X253150D01*
X252000Y576500D01*
X240500D01*
X237500Y579500D01*
X229000D01*
X226635Y581865D01*
X212349D01*
X210799Y580315D01*
X209841D01*
G01X233607Y557671D02*
X228469D01*
X223121Y563019D01*
X215498D01*
X214821Y563696D01*
X214179D01*
X214008Y563867D01*
X213692D01*
X212992Y564567D01*
G01X254500Y575070D02*
X255020Y574550D01*
X262267D01*
X263686Y575969D01*
X286235D01*
X290511Y580245D01*
X297471D01*
X300921Y576795D01*
X342861D01*
X346590Y573066D01*
Y572090D01*
G01X350278Y572306D02*
X348212Y570240D01*
X345823D01*
X344590Y571473D01*
X344589Y572238D01*
X342032Y574795D01*
X287890D01*
X287064Y573969D01*
X264515D01*
X262285Y571739D01*
X261239D01*
X261100Y571600D01*
G01X366270Y563400D02*
X365971Y563101D01*
X353276D01*
X351725Y561550D01*
X343021D01*
X338901Y565670D01*
X327130D01*
X326460Y566340D01*
X326295D01*
X324275Y568360D01*
X296868D01*
X295167Y566659D01*
X291618D01*
X289576Y564617D01*
X261983D01*
X260987Y565613D01*
X258364D01*
X257100Y566877D01*
Y568029D01*
X253709Y571420D01*
X237371D01*
X236791Y572000D01*
X234800D01*
G01X248900Y545700D02*
X248313Y545113D01*
X244487D01*
X242889Y546711D01*
X234618D01*
X230979Y550350D01*
X224289D01*
X221118Y553521D01*
X211440D01*
X209842Y555119D01*
G01X274623Y578896D02*
X275222Y578297D01*
X285281D01*
X289230Y582246D01*
X299289D01*
X302537Y578998D01*
X344357D01*
X349199Y574156D01*
X351045D01*
X352376Y572825D01*
X368817D01*
X369673Y571969D01*
X393497D01*
X393567Y571899D01*
X393912D01*
G01X243322Y597509D02*
X245735Y595096D01*
X257451D01*
X258556Y596201D01*
X275560D01*
X276887Y597528D01*
X291885D01*
X300791Y606434D01*
X306899D01*
X306900Y606435D01*
X308142D01*
X318193Y596384D01*
X331362D01*
X331994Y595752D01*
X348770D01*
X349630Y594892D01*
X363118D01*
X364014Y593996D01*
G01X234205Y598743D02*
X238851D01*
X243998Y593596D01*
X259102D01*
X260206Y594700D01*
X276181D01*
X277509Y596028D01*
X292507D01*
X301413Y604934D01*
X307521D01*
X317571Y594884D01*
X330740D01*
X331372Y594252D01*
X348148D01*
X349358Y593042D01*
X361151D01*
X362935Y591258D01*
X366550D01*
X367050Y590758D01*
Y587321D01*
X364900Y585171D01*
G01X278769Y700697D02*
X278703D01*
X278700Y700700D01*
X276500D01*
X275100Y699300D01*
X272610D01*
X270461Y701449D01*
Y701450D01*
X269961Y701950D01*
X264680D01*
X260568Y706062D01*
X253196D01*
G01X327250Y701500D02*
X326089Y701392D01*
X325597Y700900D01*
X324700D01*
X316500Y692700D01*
X297746D01*
X297745Y692701D01*
X292399D01*
X289100Y696000D01*
X230000D01*
X227550Y693550D01*
X219650D01*
X217638Y695562D01*
G01X235000Y692900D02*
X236350Y691550D01*
X262650D01*
X263499Y690701D01*
X296916D01*
X296917Y690700D01*
X321086D01*
X327162Y696776D01*
G01X262323Y716917D02*
X268987D01*
X269610Y717540D01*
X280646D01*
G01X438600Y91033D02*
Y64400D01*
X434100Y59900D01*
X395200D01*
X370850Y35550D01*
X333350D01*
X310353Y58547D01*
Y62159D01*
G01X442800Y90934D02*
Y66478D01*
X434717Y58395D01*
X395817D01*
X371472Y34050D01*
X332728D01*
X306623Y60155D01*
Y110585D01*
X296962Y120246D01*
Y159165D01*
X299107Y161310D01*
Y177740D01*
G01X366950Y464700D02*
X362400Y460150D01*
Y432462D01*
X323576Y393638D01*
X319967D01*
X311327Y384998D01*
Y168817D01*
X322123Y158021D01*
Y49606D01*
X334179Y37550D01*
X365450D01*
X370870Y42970D01*
Y45605D01*
G01X364500Y453700D02*
X364900Y453300D01*
Y432133D01*
X324405Y391638D01*
X320796D01*
X313327Y384169D01*
Y169646D01*
X324123Y158850D01*
Y50435D01*
X335008Y39550D01*
X364150D01*
X368059Y43459D01*
Y57759D01*
G01X665800Y7550D02*
X665507Y7843D01*
X322079D01*
X317472Y12450D01*
X315450D01*
X303100Y24800D01*
Y111986D01*
X295462Y119624D01*
Y173414D01*
G01X338743Y122894D02*
X335460Y126177D01*
Y161750D01*
X328712Y168498D01*
Y237402D01*
X331434Y240124D01*
Y271893D01*
X328913Y274414D01*
G01X334017Y272000D02*
X334000D01*
X332934Y270934D01*
Y239501D01*
X330212Y236779D01*
Y212484D01*
X330213Y212483D01*
Y211241D01*
X330212Y211240D01*
Y169120D01*
X336960Y162372D01*
Y127426D01*
X342539Y121847D01*
Y120370D01*
G01X369253Y88733D02*
X371634Y91114D01*
Y95143D01*
X364926Y101851D01*
X345449D01*
X332960Y114340D01*
Y160714D01*
X326211Y167463D01*
Y238437D01*
X328934Y241160D01*
Y270857D01*
X326412Y273379D01*
Y294676D01*
X325656Y295432D01*
Y301995D01*
X326300Y302639D01*
Y319986D01*
X325656Y320630D01*
Y326219D01*
X326300Y326863D01*
Y345182D01*
X325656Y345826D01*
Y351416D01*
X326400Y352160D01*
Y370228D01*
X325657Y370971D01*
Y376565D01*
X326300Y377208D01*
Y380300D01*
X332900Y386900D01*
X335400D01*
X338932Y390432D01*
Y394235D01*
X371900Y427203D01*
Y427300D01*
X372200Y427600D01*
Y451900D01*
X372000Y452100D01*
G01X369900Y458700D02*
X369557Y458357D01*
Y428396D01*
X331500Y390339D01*
Y389036D01*
X323157Y380693D01*
Y369935D01*
X323900Y369192D01*
Y353197D01*
X323156Y352453D01*
Y344790D01*
X323800Y344146D01*
Y328000D01*
X322700Y326900D01*
Y320049D01*
X323800Y318949D01*
Y303675D01*
X323156Y303031D01*
Y294396D01*
X323900Y293652D01*
Y272355D01*
X326434Y269821D01*
Y242196D01*
X318027Y233789D01*
Y171673D01*
X330460Y159240D01*
Y113304D01*
X344413Y99351D01*
X362936D01*
X365768Y96519D01*
Y78637D01*
X367287Y77118D01*
G01X353543Y70787D02*
Y73257D01*
X347200Y79600D01*
X332768D01*
X326460Y85908D01*
Y159342D01*
X315347Y170455D01*
Y234645D01*
X323934Y243232D01*
Y268785D01*
X319347Y273372D01*
Y378547D01*
X320657Y379857D01*
Y381729D01*
X329000Y390072D01*
Y391375D01*
X366900Y429275D01*
Y460700D01*
X367400Y461200D01*
G01X342885Y276301D02*
X339633Y273049D01*
Y171167D01*
X344460Y166340D01*
Y131326D01*
X347926Y127860D01*
X353698D01*
X365921Y115637D01*
X375533D01*
X393952Y97218D01*
X471462D01*
X473172Y95508D01*
G01X469901Y94047D02*
X468730Y95218D01*
X393123D01*
X374704Y113637D01*
X365092D01*
X352995Y125734D01*
X346912D01*
X342460Y130186D01*
Y165052D01*
X337633Y169879D01*
Y274376D01*
X342958Y279701D01*
G01X322301Y220009D02*
X323711Y218599D01*
Y179193D01*
X323582Y179064D01*
G01X355400Y453800D02*
Y431120D01*
X321918Y397638D01*
X305475D01*
X299282Y391445D01*
Y240874D01*
X305882Y234274D01*
G01X357900Y450800D02*
Y430791D01*
X322747Y395638D01*
X306304D01*
X301282Y390616D01*
Y242163D01*
X305772Y237673D01*
G01X316900Y384100D02*
X315347Y382547D01*
Y252353D01*
X321700Y246000D01*
G01X319679Y387121D02*
X319600Y387042D01*
Y383501D01*
X317347Y381248D01*
Y254253D01*
X321600Y250000D01*
G01X305781Y241076D02*
X309327Y244622D01*
Y385827D01*
X314000Y390500D01*
G01X335800Y379800D02*
Y380800D01*
X341713Y386713D01*
Y393480D01*
X374400Y426167D01*
Y426200D01*
X375298Y427098D01*
Y453002D01*
X372800Y455500D01*
Y462800D01*
X370900Y464700D01*
G01X338800Y435100D02*
Y442009D01*
X350491Y453700D01*
Y453809D01*
G01X355300Y506100D02*
X350300Y511100D01*
X343900D01*
X342550Y509750D01*
X337950D01*
X335900Y511800D01*
X332146D01*
X329296Y514650D01*
X302350D01*
X301350Y515650D01*
X292450D01*
X292100Y516000D01*
G01X297400Y517981D02*
X297719Y518300D01*
X302650D01*
X303800Y517150D01*
X330656D01*
X330956Y517450D01*
X333567D01*
X335652Y515365D01*
X335976D01*
X337741Y513600D01*
X355200D01*
X355300Y513500D01*
G01X378267Y496100D02*
X336678D01*
X330078Y502700D01*
X320259D01*
X317209Y505750D01*
X314400D01*
G01X400080Y523903D02*
X392033Y531950D01*
X336680D01*
X333800Y534830D01*
G01X399726Y562327D02*
X396494Y565559D01*
X386749D01*
X382955Y569353D01*
X363070D01*
X361807Y568090D01*
X344932D01*
X343102Y569920D01*
X341673D01*
X339253Y572340D01*
X330210D01*
X329840Y572710D01*
G01X337550Y534619D02*
X338219Y533950D01*
X394373D01*
X400080Y528243D01*
G01X399946Y558677D02*
X398305D01*
X393532Y563450D01*
X386029D01*
X382126Y567353D01*
X375656D01*
X371753Y563450D01*
X369170D01*
X366823Y565797D01*
X353143D01*
X350896Y563550D01*
X347533D01*
X347516Y563567D01*
X343833D01*
X337060Y570340D01*
X327953D01*
X325475Y572818D01*
G01X334900Y586100D02*
X334400Y585600D01*
X330829D01*
X328045Y588384D01*
X307162D01*
X304696Y590850D01*
X301350D01*
X299665Y589165D01*
X295929D01*
X294994Y590100D01*
X281770D01*
X281610Y590260D01*
G01X337300Y583000D02*
X337084D01*
X336484Y583600D01*
X330000D01*
X327216Y586384D01*
X306333D01*
X303867Y588850D01*
X302333D01*
X300648Y587165D01*
X295100D01*
X294165Y588100D01*
X285208D01*
X283970Y586862D01*
X281490D01*
G01X344163Y553395D02*
X339860D01*
X333955Y559300D01*
X322327D01*
X321280Y558253D01*
Y556719D01*
X320197Y555636D01*
X318379D01*
X315048Y558967D01*
X295902D01*
X294107Y560762D01*
G01X298000Y561000D02*
X298033Y560967D01*
X315877D01*
X316281Y560563D01*
X320296D01*
X321033Y561300D01*
X337613D01*
X341696Y557217D01*
X344910D01*
X345259Y557566D01*
G01X277048Y590470D02*
X279478Y592900D01*
X304024D01*
X306434Y595310D01*
X309943D01*
X312600Y592653D01*
X315084D01*
X315853Y591884D01*
X329496D01*
X330128Y591252D01*
X341894D01*
X345682Y587464D01*
X358807D01*
X362950Y583321D01*
X367645D01*
X371290Y586966D01*
X387181D01*
X391993Y582154D01*
G01X285912Y538750D02*
X288805Y541643D01*
X337832D01*
X339301Y543112D01*
X344404D01*
X346022Y544730D01*
X351830D01*
X362300Y555200D01*
G01X322889Y529380D02*
X322529D01*
X317466Y534443D01*
X289995D01*
X288312Y532760D01*
X280760D01*
X280100Y532100D01*
G01X279664Y535473D02*
X280310Y534827D01*
X287550D01*
X289166Y536443D01*
X319654D01*
X322843Y533254D01*
G01X400060Y554743D02*
X398223D01*
X395560Y557406D01*
X357012D01*
X346977Y547371D01*
X342879D01*
X334512Y555738D01*
X332028D01*
X331558Y555268D01*
X331443D01*
X327543Y551368D01*
X325687D01*
G01X276839Y582309D02*
X277909Y581239D01*
X284760D01*
X287767Y584246D01*
X307782D01*
X311029Y580999D01*
X345185D01*
X349526Y576658D01*
X367813D01*
X370142Y574329D01*
X389316D01*
X390292Y575305D01*
X393910D01*
G01X308200Y593153D02*
Y592523D01*
X310339Y590384D01*
X328874D01*
X329506Y589752D01*
X340517D01*
X346069Y584200D01*
X347111D01*
X347547Y583764D01*
X349081D01*
X349567Y584250D01*
X356272D01*
X359429Y581093D01*
Y580880D01*
X360512Y579797D01*
X366243D01*
X371912Y585466D01*
X385780D01*
X392541Y578705D01*
X393912D01*
G01X338669Y691580D02*
X343853Y696764D01*
X355864D01*
X357750Y698650D01*
X368367D01*
X368617Y698400D01*
X372350D01*
G01X340300Y703100D02*
X341550Y704350D01*
X343950D01*
X344900Y705300D01*
X349400D01*
X351700Y703000D01*
X380300D01*
G01X336200Y677000D02*
X347446D01*
X348046Y677600D01*
X357406D01*
X357706Y677300D01*
X378744D01*
X379044Y677600D01*
X392800D01*
G01X336200Y677000D02*
X330701D01*
X326151Y681550D01*
X292533D01*
X289813Y678830D01*
X289700D01*
G01X300100Y670300D02*
X300600Y670800D01*
X306600D01*
X309350Y668050D01*
X331302D01*
X331402Y667950D01*
X333018D01*
X333309Y668241D01*
X336487D01*
X341934Y662794D01*
G01X354798Y22452D02*
X363907Y13343D01*
X522173D01*
X524950Y16120D01*
G01X479147Y102165D02*
X468365D01*
X465418Y99218D01*
X406463D01*
X363856Y127406D01*
X354653Y141164D01*
X347919Y174870D01*
X345609Y177180D01*
Y252901D01*
X347482Y254774D01*
G01X387202Y164664D02*
X393955D01*
X396791Y167500D01*
Y180254D01*
X394339Y182706D01*
Y326195D01*
X375964Y344570D01*
Y357994D01*
X389444Y371474D01*
Y452383D01*
X387450Y454377D01*
Y454558D01*
G01X387393Y160859D02*
X392979D01*
X398791Y166671D01*
Y181083D01*
X396339Y183535D01*
Y327024D01*
X378570Y344793D01*
Y355987D01*
X391444Y368861D01*
Y454078D01*
X387396Y458126D01*
G01X404727Y162141D02*
Y178683D01*
X398839Y184571D01*
Y330771D01*
X392614Y336996D01*
Y358432D01*
X397944Y363762D01*
Y464388D01*
X387632Y474700D01*
X386367D01*
G01X384395Y449114D02*
Y395895D01*
X365103Y376603D01*
Y356300D01*
X367066Y354337D01*
Y337066D01*
X389839Y314293D01*
Y177647D01*
X392102Y175384D01*
G01X392458Y171676D02*
X394029Y173247D01*
Y180187D01*
X392339Y181877D01*
Y324973D01*
X373964Y343348D01*
Y367586D01*
X387444Y381066D01*
Y450271D01*
X380176Y457539D01*
X377461D01*
X374700Y460300D01*
G01X346600Y375000D02*
X347800Y376200D01*
Y386700D01*
X380798Y419698D01*
Y440933D01*
X381106Y441241D01*
G01X344732Y386874D02*
X378798Y420940D01*
Y452623D01*
X374650Y456771D01*
G01X363500Y464700D02*
X352400Y453600D01*
Y449900D01*
X342700Y440200D01*
Y435200D01*
G01X373699Y521160D02*
X357060D01*
X355000Y519100D01*
X342800D01*
X341500Y520400D01*
G01X399093Y703350D02*
X393074D01*
X388492Y698768D01*
X381423D01*
X379541Y700650D01*
X341653D01*
X340403Y699400D01*
G01X341900Y690350D02*
X346245Y694695D01*
X368278D01*
X368833Y695250D01*
X370367D01*
X370922Y694695D01*
X373915D01*
X374950Y695730D01*
X386120D01*
X387155Y694695D01*
X393899D01*
X399154Y699950D01*
G01X383800Y688400D02*
X383630Y688230D01*
X379100D01*
X373770Y682900D01*
X362071D01*
X358671Y686300D01*
X348000D01*
X346000Y684300D01*
G01X388626Y715509D02*
X388067Y714950D01*
X358498D01*
X355298Y711750D01*
G01X503814Y56676D02*
X503813Y56677D01*
X472042D01*
X471407Y56042D01*
X465380D01*
X458972Y49634D01*
G01X462625Y49881D02*
X466785Y54041D01*
X510541D01*
X513800Y57300D01*
X514900D01*
X515500Y57900D01*
G01X430800Y22200D02*
X432900Y24300D01*
X459880D01*
X461800Y26220D01*
X492680D01*
X496010Y22890D01*
X496430D01*
G01X491270Y18877D02*
X491109D01*
X486564Y23422D01*
X462222D01*
X458700Y19900D01*
X433600D01*
G01X485674Y32924D02*
X490076D01*
X497200Y25800D01*
X523582D01*
X531097Y18285D01*
X596547D01*
X601311Y13521D01*
G01X809349Y73197D02*
X810500Y74348D01*
Y76000D01*
X810000Y76500D01*
X805000D01*
X801799Y73299D01*
Y63378D01*
X789455Y51034D01*
X775952D01*
X770576Y56410D01*
X764843D01*
X751383Y42950D01*
X734281D01*
X724986Y33655D01*
X608925D01*
X604309Y38271D01*
X557810D01*
X535544Y60537D01*
Y68858D01*
X523141Y81261D01*
X519019D01*
X516685Y83595D01*
X512408D01*
X510408Y85595D01*
Y85779D01*
G01X813349Y73142D02*
X812000Y74491D01*
Y76622D01*
X810622Y78000D01*
X804378D01*
X800299Y73921D01*
Y64000D01*
X788833Y52534D01*
X776574D01*
X771198Y57910D01*
X764221D01*
X750761Y44450D01*
X733659D01*
X724364Y35155D01*
X609547D01*
X604931Y39771D01*
X558432D01*
X537044Y61159D01*
Y69480D01*
X523763Y82761D01*
X519641D01*
X516553Y85849D01*
X513909D01*
G01X551500Y82400D02*
Y82100D01*
X555900Y77700D01*
Y71700D01*
X560100Y67500D01*
X568074D01*
X569300Y66274D01*
G01X596300Y66950D02*
X615564Y47686D01*
X718655D01*
X744819Y73850D01*
X759299D01*
X769434Y83985D01*
Y90934D01*
X769500Y91000D01*
G01X549550Y61900D02*
X552500Y58950D01*
X597950D01*
G01X564500Y64100D02*
X566350D01*
X566950Y63500D01*
X570017D01*
X586400Y79883D01*
Y90433D01*
X599682Y103715D01*
G01X772800Y107550D02*
X769850Y104600D01*
Y96211D01*
X771350Y94711D01*
Y83779D01*
X758971Y71400D01*
X744900D01*
X719686Y46186D01*
X614864D01*
X599850Y61200D01*
X562300D01*
X553000Y70500D01*
Y74000D01*
X547100Y79900D01*
G01X573600Y49750D02*
X574048Y49302D01*
X608130D01*
X612746Y44686D01*
X721165D01*
X742386Y65907D01*
X755600D01*
X772850Y83157D01*
Y95333D01*
X771350Y96833D01*
Y101240D01*
X776850Y106740D01*
Y115050D01*
G01X776600Y35250D02*
X740550D01*
X729107Y23807D01*
X682515D01*
X680908Y22200D01*
X666400D01*
G01X634450Y252100D02*
X636850Y254500D01*
X637309D01*
X637809Y255000D01*
Y256600D01*
X638309Y257100D01*
X639309D01*
X639809Y256600D01*
Y255000D01*
X640309Y254500D01*
X641309D01*
X641809Y255000D01*
Y256600D01*
X642309Y257100D01*
X643309D01*
X643809Y256600D01*
Y255000D01*
X644309Y254500D01*
X645309D01*
X645809Y255000D01*
Y256600D01*
X646309Y257100D01*
X647309D01*
X647809Y256600D01*
Y255000D01*
X648309Y254500D01*
X649309D01*
X649809Y255000D01*
Y255700D01*
X650309Y256200D01*
X651221D01*
X651809Y255612D01*
Y255000D01*
X652309Y254500D01*
X652921D01*
X652922Y254499D01*
X654578D01*
X654579Y254500D01*
X656449D01*
X683049Y227900D01*
X684595D01*
X690745Y221750D01*
X698893D01*
X699006Y221637D01*
X700042D01*
X700192Y221487D01*
G01X708900Y214500D02*
X707700Y215700D01*
X704456D01*
X702506Y217650D01*
X700058D01*
X697958Y219750D01*
X689916D01*
X683766Y225900D01*
X678911D01*
X677574Y227237D01*
Y227945D01*
X678285Y228656D01*
Y229364D01*
X677578Y230071D01*
X676870D01*
X676159Y229360D01*
X675451D01*
X674744Y230067D01*
Y230775D01*
X675455Y231486D01*
Y232194D01*
X674748Y232901D01*
X674040D01*
X673329Y232190D01*
X672621D01*
X671914Y232897D01*
Y233605D01*
X672625Y234316D01*
Y235024D01*
X671918Y235731D01*
X671210D01*
X670499Y235020D01*
X669791D01*
X669084Y235727D01*
Y236435D01*
X669795Y237146D01*
Y237854D01*
X669088Y238561D01*
X668380D01*
X667669Y237850D01*
X666961D01*
X666254Y238557D01*
Y239265D01*
X666965Y239976D01*
Y240684D01*
X666258Y241391D01*
X665550D01*
X664839Y240680D01*
X664131D01*
X663424Y241387D01*
Y242095D01*
X664135Y242806D01*
Y243514D01*
X663428Y244221D01*
X662720D01*
X662009Y243510D01*
X661301D01*
X660594Y244217D01*
Y244925D01*
X661305Y245636D01*
Y246344D01*
X660598Y247051D01*
X659890D01*
X659179Y246340D01*
X658471D01*
X657764Y247047D01*
Y247755D01*
X658475Y248466D01*
Y249174D01*
X657768Y249881D01*
X657060D01*
X656349Y249170D01*
X655641D01*
X654311Y250500D01*
Y251750D01*
X653811Y252250D01*
X652811D01*
X652311Y251750D01*
Y250500D01*
X651811Y250000D01*
X650811D01*
X650311Y250500D01*
Y251750D01*
X649811Y252250D01*
X648811D01*
X648311Y251750D01*
Y250500D01*
X647811Y250000D01*
X646811D01*
X646311Y250500D01*
Y251750D01*
X645811Y252250D01*
X644811D01*
X644311Y251750D01*
Y250500D01*
X643811Y250000D01*
X642811D01*
X642311Y250500D01*
Y251750D01*
X641811Y252250D01*
X640811D01*
X640311Y251750D01*
Y250500D01*
X639811Y250000D01*
X631700D01*
X631550Y249850D01*
G01X699350Y227900D02*
X696350D01*
X688750Y235500D01*
Y237799D01*
X679699Y246850D01*
X672586D01*
X658936Y260500D01*
X655421D01*
X649971Y265950D01*
X645134D01*
X644634Y266450D01*
Y270200D01*
X644134Y270700D01*
X643134D01*
X642634Y270200D01*
Y264534D01*
X642000Y263900D01*
X640118D01*
X639618Y264400D01*
Y265450D01*
X639118Y265950D01*
X638118D01*
X637618Y265450D01*
Y264400D01*
X637118Y263900D01*
X636118D01*
X635618Y264400D01*
Y265450D01*
X635118Y265950D01*
X631600D01*
X631100Y266450D01*
Y267894D01*
X631600Y268394D01*
X639650D01*
X640150Y268894D01*
Y269894D01*
X639650Y270394D01*
X627150D01*
X626650Y270894D01*
Y271894D01*
X627150Y272394D01*
X632900D01*
X633400Y272894D01*
Y274600D01*
G01X706500Y212150D02*
Y213350D01*
X705500Y214350D01*
X703487D01*
X702987Y214850D01*
Y215150D01*
X702487Y215650D01*
X701487D01*
X700987Y215150D01*
Y214850D01*
X700487Y214350D01*
X698871D01*
X698300Y214921D01*
Y216579D01*
X697129Y217750D01*
X689087D01*
X682937Y223900D01*
X678082D01*
X654431Y247551D01*
X643500D01*
X643000Y247051D01*
Y246051D01*
X643500Y245551D01*
X652650D01*
X653150Y245051D01*
Y244051D01*
X652650Y243551D01*
X642465D01*
X638016Y248000D01*
X627142D01*
X626672Y247530D01*
X625926D01*
G01X699100Y225900D02*
X692641D01*
X686108Y232433D01*
Y237059D01*
X684017Y239150D01*
X681079D01*
X675740Y244489D01*
X672118D01*
X658107Y258500D01*
X654592D01*
X651292Y261800D01*
X635750D01*
X634647Y260697D01*
X633939D01*
X629397Y265239D01*
X628689D01*
X627982Y264532D01*
Y263824D01*
X634749Y257057D01*
Y256349D01*
X634042Y255642D01*
X633334D01*
X626567Y262409D01*
X625859D01*
X625152Y261702D01*
Y260994D01*
X629694Y256452D01*
Y255744D01*
X627500Y253550D01*
X627200D01*
G01X625250Y264250D02*
X624650Y264850D01*
Y272723D01*
X627681Y275754D01*
X628387D01*
X629441Y274699D01*
X630147D01*
X630856Y275408D01*
Y276114D01*
X629802Y277169D01*
Y277875D01*
X631727Y279800D01*
X641779D01*
X644679Y276900D01*
X653301D01*
X655601Y274600D01*
X662850D01*
X673350Y264100D01*
X690649D01*
X692699Y266150D01*
X694567D01*
X700885Y259832D01*
Y256400D01*
X703250Y254035D01*
Y246501D01*
X702100Y245351D01*
Y236836D01*
X707443Y231493D01*
X710363D01*
X710863Y231993D01*
Y233350D01*
X711363Y233850D01*
X712363D01*
X712863Y233350D01*
Y231993D01*
X713755Y231101D01*
X718111D01*
G01X625550Y244150D02*
X626121D01*
X627971Y246000D01*
X637187D01*
X641637Y241550D01*
X657603D01*
X677253Y221900D01*
X682108D01*
X688258Y215750D01*
X696300D01*
G01X625550Y240750D02*
X628800Y244000D01*
X636358D01*
X640808Y239550D01*
X656774D01*
X676424Y219900D01*
X681279D01*
X687429Y213750D01*
X692150D01*
X693550Y212350D01*
X702900D01*
G01X652850Y269600D02*
X657950Y264500D01*
X660594D01*
X669444Y255650D01*
X672862D01*
X673362Y255150D01*
Y252050D01*
X673862Y251550D01*
X674862D01*
X675362Y252050D01*
Y255150D01*
X675862Y255650D01*
X682554D01*
X683054Y256150D01*
Y257150D01*
X682554Y257650D01*
X670700D01*
X666254Y262096D01*
Y262804D01*
X666961Y263511D01*
X667669D01*
X671530Y259650D01*
X684554D01*
X685054Y259150D01*
Y256150D01*
X685554Y255650D01*
X686079D01*
X695326Y246403D01*
Y245697D01*
X694768Y245140D01*
Y244434D01*
X695477Y243725D01*
X696183D01*
X696741Y244282D01*
X697447D01*
X698450Y243279D01*
Y239868D01*
X697950Y239368D01*
X695400D01*
X694900Y238868D01*
Y237868D01*
X695400Y237368D01*
X697950D01*
X698450Y236868D01*
Y236022D01*
X699639Y234833D01*
Y234125D01*
X699086Y233572D01*
Y232864D01*
X699793Y232157D01*
X700501D01*
X701054Y232710D01*
X701762D01*
X702836Y231636D01*
G01X645516Y225334D02*
X650565D01*
X677639Y198260D01*
X680887D01*
X685697Y193450D01*
X715579D01*
X720371Y198242D01*
Y198984D01*
X722322Y200935D01*
G01X704279Y226664D02*
Y227054D01*
X703603Y227730D01*
Y228046D01*
X701749Y229900D01*
X697179D01*
X695541Y231538D01*
Y232244D01*
X696995Y233697D01*
Y234403D01*
X696286Y235112D01*
X695580D01*
X694126Y233659D01*
X693420D01*
X692750Y234329D01*
Y238467D01*
X691667Y239550D01*
X689829D01*
X688930Y240448D01*
Y241154D01*
X692734Y244958D01*
Y245665D01*
X692025Y246374D01*
X691319D01*
X687514Y242569D01*
X686809D01*
X686100Y243278D01*
Y243985D01*
X690080Y247965D01*
Y248671D01*
X689372Y249379D01*
X688665D01*
X684685Y245399D01*
X683979D01*
X683270Y246108D01*
Y246814D01*
X687250Y250794D01*
Y251501D01*
X686541Y252210D01*
X685835D01*
X682475Y248850D01*
X679918D01*
X679418Y249350D01*
Y253100D01*
X678918Y253600D01*
X677918D01*
X677418Y253100D01*
Y249350D01*
X676918Y248850D01*
X673415D01*
X659765Y262500D01*
X656920D01*
X650156Y269264D01*
X649448D01*
X648246Y268062D01*
X647538D01*
X646831Y268769D01*
Y269477D01*
X648033Y270679D01*
Y271387D01*
X646720Y272700D01*
X636600D01*
X635950Y273350D01*
Y277100D01*
X636650Y277800D01*
X640950D01*
X642300Y276450D01*
G01X701075Y236226D02*
X700450Y236851D01*
Y244108D01*
X696147Y248411D01*
Y249119D01*
X699510Y252482D01*
Y253190D01*
X698803Y253897D01*
X698095D01*
X694732Y250534D01*
X694024D01*
X693317Y251241D01*
Y251949D01*
X698780Y257412D01*
Y258120D01*
X698073Y258827D01*
X697365D01*
X691902Y253364D01*
X691194D01*
X690487Y254071D01*
Y254779D01*
X696125Y260417D01*
Y261125D01*
X695418Y261832D01*
X694710D01*
X689072Y256194D01*
X688364D01*
X687054Y257504D01*
Y259979D01*
X685383Y261650D01*
X672450D01*
X667289Y266811D01*
X666581D01*
X664459Y264689D01*
X663751D01*
X659574Y268866D01*
Y269574D01*
X660281Y270281D01*
X660989D01*
X663751Y267519D01*
X664459D01*
X665166Y268226D01*
Y268934D01*
X661500Y272600D01*
X658006D01*
X657506Y272100D01*
Y270100D01*
X657006Y269600D01*
X656006D01*
X655506Y270100D01*
Y272100D01*
X655006Y272600D01*
X649900D01*
X649000Y273500D01*
G01X620750Y258050D02*
Y267050D01*
X622206Y268506D01*
Y273108D01*
X630898Y281800D01*
X643762D01*
X646212Y279350D01*
X649321D01*
X651272Y281301D01*
X654558D01*
X657259Y278600D01*
X687775D01*
X696225Y270150D01*
X697149D01*
X701772Y265527D01*
X705073D01*
X708850Y261750D01*
Y243435D01*
X706079Y240664D01*
G01X726988Y204312D02*
X726176Y203500D01*
X721749D01*
X719773Y201524D01*
Y200417D01*
X718807Y199451D01*
X718751D01*
X714750Y195450D01*
X686526D01*
X681326Y200650D01*
X678700D01*
X651800Y227550D01*
X643500D01*
X642942Y226992D01*
X642547D01*
G01X718123Y201101D02*
X714252D01*
X710601Y197450D01*
X687355D01*
X677305Y207500D01*
X674679D01*
X652629Y229550D01*
X634850D01*
X633400Y231000D01*
X632958D01*
G01X710079Y203664D02*
X708315Y201900D01*
X708100D01*
X705650Y199450D01*
X688184D01*
X678134Y209500D01*
X675508D01*
X653458Y231550D01*
X636144D01*
X633297Y234397D01*
X633109D01*
G01X718895Y207125D02*
X717270Y205500D01*
X715552D01*
X715052Y205000D01*
Y202900D01*
X714552Y202400D01*
X713552D01*
X713052Y202900D01*
Y205000D01*
X712552Y205500D01*
X709450D01*
X706200Y202250D01*
X700550D01*
X699050Y203750D01*
X686910D01*
X679160Y211500D01*
X676337D01*
X654287Y233550D01*
X638321D01*
X633871Y238000D01*
X632900D01*
G01X628300Y230550D02*
X628150Y230700D01*
Y236400D01*
X631750Y240000D01*
X634700D01*
X639150Y235550D01*
X655116D01*
X677166Y213500D01*
X680499D01*
X688249Y205750D01*
X705250D01*
X705364Y205864D01*
G01X625700Y235750D02*
Y236751D01*
X626150Y237201D01*
Y237229D01*
X630921Y242000D01*
X635529D01*
X639979Y237550D01*
X655945D01*
X675595Y217900D01*
X679200D01*
X687207Y209893D01*
X710964D01*
X713168Y207689D01*
G01X640141Y259859D02*
X640250Y259750D01*
X650500D01*
X653750Y256500D01*
X657278D01*
X672392Y241386D01*
X673100D01*
X674203Y242489D01*
X674911D01*
X675618Y241782D01*
Y241074D01*
X674515Y239971D01*
Y239263D01*
X675222Y238556D01*
X675930D01*
X677033Y239659D01*
X677741D01*
X678448Y238952D01*
Y238244D01*
X677345Y237141D01*
Y236433D01*
X678052Y235726D01*
X678760D01*
X679863Y236829D01*
X680571D01*
X681278Y236122D01*
Y235414D01*
X680175Y234311D01*
Y233603D01*
X680882Y232896D01*
X681590D01*
X682693Y233999D01*
X683401D01*
X684108Y233292D01*
Y232584D01*
X683005Y231481D01*
Y230773D01*
X683878Y229900D01*
X685424D01*
X691574Y223750D01*
X698500D01*
G01X718098Y259423D02*
X713950Y263571D01*
Y266957D01*
X704756Y276151D01*
X698711D01*
X691433Y283429D01*
Y286575D01*
X683657Y294351D01*
X682001D01*
X682000Y294350D01*
X678008D01*
X678006Y294352D01*
X676350D01*
X676349Y294351D01*
X674693D01*
X674692Y294350D01*
X668542D01*
X666392Y292200D01*
X660700D01*
G01X692750Y293200D02*
X689849Y296101D01*
X687565D01*
X685315Y298351D01*
X680343D01*
X680342Y298350D01*
X679666D01*
X679664Y298352D01*
X673036D01*
X673034Y298350D01*
X666884D01*
X664734Y296200D01*
X659042D01*
X658943Y296101D01*
X656072D01*
X650421Y290450D01*
X644973D01*
X641474Y293949D01*
X636684D01*
X634830Y292095D01*
G01X694307Y283485D02*
X693433Y284359D01*
Y287404D01*
X692100Y288737D01*
Y290650D01*
X688649Y294101D01*
X686736D01*
X684486Y296351D01*
X681172D01*
X681171Y296350D01*
X678837D01*
X678835Y296352D01*
X673865D01*
X673863Y296350D01*
X667713D01*
X665563Y294200D01*
X659871D01*
X659772Y294101D01*
X656901D01*
X651000Y288200D01*
X642000D01*
X638453Y291747D01*
Y291949D01*
G01X707679Y233664D02*
X708029Y234014D01*
Y239848D01*
X710000Y241819D01*
Y247941D01*
X710500Y248441D01*
X713250D01*
X713750Y248941D01*
Y249941D01*
X713250Y250441D01*
X710500D01*
X710000Y250941D01*
Y251941D01*
X710500Y252441D01*
X713250D01*
X713750Y252941D01*
Y253941D01*
X713250Y254441D01*
X710500D01*
X710000Y254941D01*
Y255941D01*
X710500Y256441D01*
X713250D01*
X713750Y256941D01*
Y257941D01*
X713250Y258441D01*
X710500D01*
X710000Y258941D01*
Y262199D01*
X705099Y267100D01*
X703028D01*
X697978Y272150D01*
X697970D01*
X697969Y272151D01*
X697053D01*
X688604Y280600D01*
X662854D01*
X662354Y281100D01*
Y282100D01*
X662854Y282600D01*
X686100D01*
X686600Y283100D01*
Y284100D01*
X686100Y284600D01*
X660854D01*
X660354Y284100D01*
Y281100D01*
X659854Y280600D01*
X658400D01*
X657500Y281500D01*
G01X705779Y236764D02*
X704429Y238114D01*
Y241429D01*
X707750Y244750D01*
Y261127D01*
X705263Y263614D01*
X699932D01*
X695346Y268200D01*
X689151D01*
X688495Y268856D01*
Y274600D01*
X687995Y275100D01*
X686995D01*
X686495Y274600D01*
Y266750D01*
X685995Y266250D01*
X684995D01*
X684495Y266750D01*
Y274950D01*
X683995Y275450D01*
X682995D01*
X682495Y274950D01*
Y266750D01*
X681995Y266250D01*
X680995D01*
X680495Y266750D01*
Y274750D01*
X679995Y275250D01*
X678995D01*
X678495Y274750D01*
Y266750D01*
X677995Y266250D01*
X676995D01*
X676495Y266750D01*
Y274900D01*
X675995Y275400D01*
X674995D01*
X674495Y274900D01*
Y268150D01*
X673995Y267650D01*
X672995D01*
X672495Y268150D01*
Y269748D01*
X671995Y270248D01*
X670502D01*
X664150Y276600D01*
X656430D01*
X654130Y278900D01*
X652500D01*
X652100Y279300D01*
G01X743279Y212196D02*
X739483D01*
X737843Y210556D01*
X723254D01*
X719685Y214125D01*
G01X716510Y245259D02*
X714800Y246969D01*
Y259549D01*
X700198Y274151D01*
X697882D01*
X689433Y282600D01*
Y285746D01*
X682829Y292350D01*
X669371D01*
X667171Y290150D01*
X658179D01*
X658178Y290151D01*
X656522D01*
X650264Y283893D01*
Y283564D01*
X648000Y281300D01*
G01X718137Y275186D02*
X715650Y277673D01*
Y282878D01*
X694278Y304250D01*
X660674D01*
X657367Y307557D01*
X649840D01*
X638603Y296320D01*
G01X642003Y296249D02*
X643873Y294379D01*
X647029D01*
X651702Y299052D01*
X664757D01*
X666055Y300350D01*
X672205D01*
X672207Y300352D01*
X680493D01*
X680494Y300351D01*
X686144D01*
X687443Y299052D01*
X688874D01*
X689812Y298114D01*
X690665D01*
X702939Y285840D01*
Y281484D01*
G01X645403Y296229D02*
X650988Y301814D01*
X665526D01*
X665562Y301850D01*
X671583D01*
X671585Y301852D01*
X679871D01*
X679872Y301853D01*
X681114D01*
X681116Y301851D01*
X686766D01*
X686803Y301814D01*
X694592D01*
X705284Y291122D01*
Y282489D01*
X710059Y277714D01*
Y276984D01*
X718109Y268934D01*
G01X714949Y287814D02*
X710850Y291913D01*
Y299050D01*
X699900Y310000D01*
X690450D01*
X687450Y307000D01*
X666317D01*
X665367Y307950D01*
X665050D01*
X663000Y310000D01*
X648706D01*
X634265Y295559D01*
X634116D01*
X631069Y292512D01*
G01X629239Y387969D02*
Y390349D01*
X642962Y404072D01*
X674172D01*
X683341Y413241D01*
X698394D01*
X701429Y410206D01*
X709006D01*
G01X620100Y384100D02*
X621631Y385631D01*
X633098D01*
X646109Y398642D01*
X646896D01*
X646897Y398643D01*
X648967D01*
X648968Y398642D01*
X717825D01*
X721504Y402321D01*
G01X632220Y389694D02*
X643941Y401415D01*
X689488D01*
X691873Y403800D01*
G01X735300Y401957D02*
X728257D01*
X722442Y396142D01*
X647932D01*
X634921Y383131D01*
X622667D01*
X621135Y381599D01*
X619065D01*
X618321Y382343D01*
X608057D01*
X608038Y382362D01*
X607800D01*
G01X677770Y196410D02*
X682730Y191450D01*
X713408D01*
X713908Y190950D01*
Y189950D01*
X713408Y189450D01*
X688500D01*
X688000Y188950D01*
Y187950D01*
X688500Y187450D01*
X701157D01*
X701657Y186950D01*
Y185950D01*
X701157Y185450D01*
X689200D01*
X688700Y184950D01*
Y183950D01*
X689200Y183450D01*
X703157D01*
X703657Y183950D01*
Y186950D01*
X704157Y187450D01*
X715408D01*
X715908Y187950D01*
Y190950D01*
X725466Y200508D01*
Y200819D01*
G01X694307Y283485D02*
Y283384D01*
X699540Y278151D01*
X704029D01*
X705129Y277051D01*
X705130D01*
X705656Y276525D01*
Y276524D01*
X707430Y274750D01*
X707431D01*
X707957Y274224D01*
Y274223D01*
X714853Y267327D01*
Y266547D01*
X719670Y261730D01*
G01X691813Y407210D02*
X693325D01*
X694829Y405706D01*
X734380D01*
X741086Y399000D01*
X806100D01*
X806400Y398700D01*
G01X810100Y404934D02*
X806166Y401000D01*
X741915D01*
X735209Y407706D01*
X695658D01*
X692623Y410741D01*
X691874D01*
G01X886540Y388996D02*
Y398118D01*
X877758Y406900D01*
X869300D01*
X862800Y413400D01*
X806600D01*
X796200Y403000D01*
X742744D01*
X736038Y409706D01*
X724094D01*
X720900Y412900D01*
G01X736600Y500000D02*
X734700Y498100D01*
X732600D01*
X715400Y480900D01*
Y479118D01*
X715391Y479109D01*
G01X787402Y240552D02*
X787403D01*
X792210Y245359D01*
X795141D01*
X797608Y242892D01*
Y238821D01*
X804729Y231700D01*
X816900D01*
G01X738160Y199480D02*
X739550D01*
X748370Y208300D01*
Y218090D01*
X747840Y218620D01*
X740858D01*
X738987Y220491D01*
G01X883240Y301973D02*
X877107Y308106D01*
X866906D01*
X852800Y322212D01*
Y355365D01*
X839388Y368777D01*
X810390D01*
X801386Y377781D01*
X790357D01*
M02*
